FILE_TYPE = MACRO_DRAWING;
SET COLOR_WIRE YELLOW;
SET COLOR_PROP ORANGE;
SET COLOR_DOT WHITE;
SET COLOR_ARC YELLOW;
SET COLOR_BODY GREEN;
SET COLOR_NOTE PURPLE;
SET PROP_DISPLAY VALUE;
SET PAGE_NUMBER P170;
FORCEADD UNIVERSAL_GND..1
(-7775 4350);
FORCEPROP 3 LASTPIN (-7775 4400) SIG_NAME GND\g
J 0
(-7765 4410);
DISPLAY 0.659574 (-7765 4410);
PAINT MONO (-7765 4410);
DISPLAY INVISIBLE (-7765 4410);
FORCEPROP 2 LAST CDS_LIB pure_quanta_power
J 0
(-7775 4350);
DISPLAY INVISIBLE (-7775 4350);
FORCEPROP 1 LAST PATH I1
J 0
(-7700 4350);
DISPLAY 0.872340 (-7700 4350);
PAINT AQUA (-7700 4350);
DISPLAY INVISIBLE (-7700 4350);
FORCEPROP 1 LAST HDL_POWER GND
J 1
(-7750 4275);
DISPLAY 0.872340 (-7750 4275);
PAINT GREEN (-7750 4275);
DISPLAY INVISIBLE (-7750 4275);
FORCEADD OFFPAGE..2
R 2
(-7000 1100);
FORCEPROP 2 LAST $XR3 169 
J 0
(-7495 1064);
DISPLAY 0.638298 (-7495 1064);
PAINT MONO (-7495 1064);
FORCEPROP 2 LAST $XR2 172 
J 0
(-7375 1064);
DISPLAY 0.638298 (-7375 1064);
PAINT MONO (-7375 1064);
FORCEPROP 2 LAST $XR1 171 
J 0
(-7255 1064);
DISPLAY 0.638298 (-7255 1064);
PAINT MONO (-7255 1064);
FORCEPROP 2 LAST $XR0 170 
J 0
(-7255 1100);
DISPLAY 0.638298 (-7255 1100);
PAINT MONO (-7255 1100);
FORCEPROP 2 LAST PATH I101
J 0
(-6950 1175);
DISPLAY 1.021277 (-6950 1175);
DISPLAY INVISIBLE (-6950 1175);
FORCEPROP 1 LAST COMMENT_BODY TRUE
J 2
(-6955 1005);
DISPLAY 0.872340 (-6955 1005);
PAINT GREEN (-6955 1005);
DISPLAY INVISIBLE (-6955 1005);
FORCEPROP 1 LAST OFFPAGE TRUE
J 2
(-7325 975);
DISPLAY 0.872340 (-7325 975);
PAINT GREEN (-7325 975);
DISPLAY INVISIBLE (-7325 975);
FORCEPROP 2 LAST CDS_LIB standard
J 0
(-7000 1100);
DISPLAY INVISIBLE (-7000 1100);
FORCEADD UNIVERSAL_GND..1
(-7375 1125);
FORCEPROP 3 LASTPIN (-7375 1175) SIG_NAME GND\g
J 0
(-7365 1185);
DISPLAY 0.659574 (-7365 1185);
PAINT MONO (-7365 1185);
DISPLAY INVISIBLE (-7365 1185);
FORCEPROP 2 LAST CDS_LIB pure_quanta_power
J 0
(-7375 1125);
DISPLAY INVISIBLE (-7375 1125);
FORCEPROP 1 LAST PATH I102
J 0
(-7300 1125);
DISPLAY 0.872340 (-7300 1125);
PAINT AQUA (-7300 1125);
DISPLAY INVISIBLE (-7300 1125);
FORCEPROP 1 LAST HDL_POWER GND
J 1
(-7350 1050);
DISPLAY 0.872340 (-7350 1050);
PAINT GREEN (-7350 1050);
DISPLAY INVISIBLE (-7350 1050);
FORCEADD OFFPAGE..1
(-6975 1000);
FORCEPROP 2 LAST $XR0 169 
J 0
(-7227 1000);
DISPLAY 0.638298 (-7227 1000);
PAINT MONO (-7227 1000);
FORCEPROP 2 LAST PATH I103
J 0
(-6925 1075);
DISPLAY 1.021277 (-6925 1075);
DISPLAY INVISIBLE (-6925 1075);
FORCEPROP 1 LAST COMMENT_BODY TRUE
J 0
(-6850 900);
DISPLAY 0.872340 (-6850 900);
PAINT GREEN (-6850 900);
DISPLAY INVISIBLE (-6850 900);
FORCEPROP 1 LAST OFFPAGE TRUE
J 0
(-6650 875);
DISPLAY 0.872340 (-6650 875);
PAINT GREEN (-6650 875);
DISPLAY INVISIBLE (-6650 875);
FORCEPROP 2 LAST CDS_LIB standard
J 2
(-6975 1000);
DISPLAY INVISIBLE (-6975 1000);
FORCEADD OFFPAGE..1
(-7925 1500);
FORCEPROP 2 LAST $XR5 175 
J 0
(-8807 1500);
DISPLAY 0.638298 (-8807 1500);
PAINT MONO (-8807 1500);
FORCEPROP 2 LAST $XR4 174 
J 0
(-8687 1500);
DISPLAY 0.638298 (-8687 1500);
PAINT MONO (-8687 1500);
FORCEPROP 2 LAST $XR3 172 
J 0
(-8567 1500);
DISPLAY 0.638298 (-8567 1500);
PAINT MONO (-8567 1500);
FORCEPROP 2 LAST $XR2 171 
J 0
(-8447 1500);
DISPLAY 0.638298 (-8447 1500);
PAINT MONO (-8447 1500);
FORCEPROP 2 LAST $XR1 170 
J 0
(-8327 1500);
DISPLAY 0.638298 (-8327 1500);
PAINT MONO (-8327 1500);
FORCEPROP 2 LAST $XR0 169 
J 0
(-8207 1500);
DISPLAY 0.638298 (-8207 1500);
PAINT MONO (-8207 1500);
FORCEPROP 2 LAST PATH I104
J 0
(-7875 1575);
DISPLAY 1.021277 (-7875 1575);
DISPLAY INVISIBLE (-7875 1575);
FORCEPROP 1 LAST COMMENT_BODY TRUE
J 0
(-7800 1400);
DISPLAY 0.872340 (-7800 1400);
PAINT GREEN (-7800 1400);
DISPLAY INVISIBLE (-7800 1400);
FORCEPROP 1 LAST OFFPAGE TRUE
J 0
(-7600 1375);
DISPLAY 0.872340 (-7600 1375);
PAINT GREEN (-7600 1375);
DISPLAY INVISIBLE (-7600 1375);
FORCEPROP 2 LAST CDS_LIB standard
J 0
(-7925 1500);
DISPLAY INVISIBLE (-7925 1500);
FORCEADD Q_CAP..1
(-7700 1325);
FORCEPROP 1 LAST LOCATION PC545_4
J 0
(-7650 1425);
DISPLAY 0.489362 (-7650 1425);
PAINT SKYBLUE (-7650 1425);
FORCEPROP 0 LAST $SEC 1
J 0
(-7650 1450);
DISPLAY 0.680851 (-7650 1450);
PAINT MONO (-7650 1450);
DISPLAY INVISIBLE (-7650 1450);
FORCEPROP 0 LAST CDS_SEC 1
J 0
(-7650 1450);
DISPLAY 1.021277 (-7650 1450);
DISPLAY INVISIBLE (-7650 1450);
FORCEPROP 1 LASTPIN (-7700 1425) $PN 1
J 0
(-7690 1405);
DISPLAY 0.489362 (-7690 1405);
PAINT MONO (-7690 1405);
FORCEPROP 1 LASTPIN (-7700 1225) $PN 2
J 0
(-7690 1205);
DISPLAY 0.489362 (-7690 1205);
PAINT MONO (-7690 1205);
FORCEPROP 1 LAST MATERIAL X7R
J 0
(-7650 1225);
DISPLAY 0.489362 (-7650 1225);
PAINT SKYBLUE (-7650 1225);
FORCEPROP 1 LAST TOLERANCE 10%
J 0
(-7650 1275);
DISPLAY 0.489362 (-7650 1275);
PAINT SKYBLUE (-7650 1275);
FORCEPROP 1 LAST VALUE 0.1UF
J 0
(-7650 1375);
DISPLAY 0.489362 (-7650 1375);
PAINT SKYBLUE (-7650 1375);
FORCEPROP 1 LAST PART_NUMBER CH4104K1B00
J 0
(-7650 1175);
DISPLAY 0.489362 (-7650 1175);
PAINT SKYBLUE (-7650 1175);
FORCEPROP 1 LAST VOLTAGE 25V
J 0
(-7650 1325);
DISPLAY 0.489362 (-7650 1325);
PAINT SKYBLUE (-7650 1325);
FORCEPROP 1 LAST PACK_TYPE 0402
J 0
(-7650 1125);
DISPLAY 0.489362 (-7650 1125);
PAINT SKYBLUE (-7650 1125);
FORCEPROP 2 LAST CDS_LIB pure_quanta
J 0
(-7700 1325);
DISPLAY INVISIBLE (-7700 1325);
FORCEPROP 1 LAST PATH I105
J 0
(-7650 1475);
DISPLAY 0.978723 (-7650 1475);
PAINT WHITE (-7650 1475);
DISPLAY INVISIBLE (-7650 1475);
FORCEADD UNIVERSAL_GND..1
(-7700 1050);
FORCEPROP 3 LASTPIN (-7700 1100) SIG_NAME GND\g
J 0
(-7690 1110);
DISPLAY 0.659574 (-7690 1110);
PAINT MONO (-7690 1110);
DISPLAY INVISIBLE (-7690 1110);
FORCEPROP 2 LAST CDS_LIB pure_quanta_power
J 0
(-7700 1050);
DISPLAY INVISIBLE (-7700 1050);
FORCEPROP 1 LAST PATH I106
J 0
(-7625 1050);
DISPLAY 0.872340 (-7625 1050);
PAINT AQUA (-7625 1050);
DISPLAY INVISIBLE (-7625 1050);
FORCEPROP 1 LAST HDL_POWER GND
J 1
(-7675 975);
DISPLAY 0.872340 (-7675 975);
PAINT GREEN (-7675 975);
DISPLAY INVISIBLE (-7675 975);
FORCEADD Q_CAP..1
(-5325 5800);
FORCEPROP 1 LAST LOCATION PC550_3
J 0
(-5275 5900);
DISPLAY 0.489362 (-5275 5900);
PAINT SKYBLUE (-5275 5900);
FORCEPROP 0 LAST $SEC 1
J 0
(-5275 5950);
DISPLAY 0.680851 (-5275 5950);
PAINT MONO (-5275 5950);
DISPLAY INVISIBLE (-5275 5950);
FORCEPROP 0 LAST CDS_SEC 1
J 0
(-5275 5950);
DISPLAY 1.021277 (-5275 5950);
DISPLAY INVISIBLE (-5275 5950);
FORCEPROP 1 LASTPIN (-5325 5900) $PN 1
J 0
(-5315 5880);
DISPLAY 0.489362 (-5315 5880);
PAINT MONO (-5315 5880);
FORCEPROP 1 LASTPIN (-5325 5700) $PN 2
J 0
(-5315 5680);
DISPLAY 0.489362 (-5315 5680);
PAINT MONO (-5315 5680);
FORCEPROP 1 LAST MATERIAL X7R
J 0
(-5275 5700);
DISPLAY 0.489362 (-5275 5700);
PAINT SKYBLUE (-5275 5700);
FORCEPROP 1 LAST TOLERANCE 10%
J 0
(-5275 5750);
DISPLAY 0.489362 (-5275 5750);
PAINT SKYBLUE (-5275 5750);
FORCEPROP 1 LAST VALUE 0.1UF
J 0
(-5275 5850);
DISPLAY 0.489362 (-5275 5850);
PAINT SKYBLUE (-5275 5850);
FORCEPROP 1 LAST PART_NUMBER CH4104K1B00
J 0
(-5275 5650);
DISPLAY 0.489362 (-5275 5650);
PAINT SKYBLUE (-5275 5650);
FORCEPROP 1 LAST VOLTAGE 25V
J 0
(-5275 5800);
DISPLAY 0.489362 (-5275 5800);
PAINT SKYBLUE (-5275 5800);
FORCEPROP 1 LAST PACK_TYPE 0402
J 0
(-5275 5600);
DISPLAY 0.489362 (-5275 5600);
PAINT SKYBLUE (-5275 5600);
FORCEPROP 2 LAST CDS_LIB pure_quanta
J 0
(-5325 5800);
DISPLAY INVISIBLE (-5325 5800);
FORCEPROP 1 LAST PATH I107
J 0
(-5275 5950);
DISPLAY 0.978723 (-5275 5950);
PAINT WHITE (-5275 5950);
DISPLAY INVISIBLE (-5275 5950);
FORCEADD Q_CAP..1
(-5200 2500);
FORCEPROP 1 LAST LOCATION PC551_4
J 0
(-5150 2600);
DISPLAY 0.489362 (-5150 2600);
PAINT SKYBLUE (-5150 2600);
FORCEPROP 0 LAST $SEC 1
J 0
(-5150 2650);
DISPLAY 0.680851 (-5150 2650);
PAINT MONO (-5150 2650);
DISPLAY INVISIBLE (-5150 2650);
FORCEPROP 0 LAST CDS_SEC 1
J 0
(-5150 2650);
DISPLAY 1.021277 (-5150 2650);
DISPLAY INVISIBLE (-5150 2650);
FORCEPROP 1 LASTPIN (-5200 2600) $PN 1
J 0
(-5190 2580);
DISPLAY 0.489362 (-5190 2580);
PAINT MONO (-5190 2580);
FORCEPROP 1 LASTPIN (-5200 2400) $PN 2
J 0
(-5190 2380);
DISPLAY 0.489362 (-5190 2380);
PAINT MONO (-5190 2380);
FORCEPROP 1 LAST MATERIAL X7R
J 0
(-5150 2400);
DISPLAY 0.489362 (-5150 2400);
PAINT SKYBLUE (-5150 2400);
FORCEPROP 1 LAST TOLERANCE 10%
J 0
(-5150 2450);
DISPLAY 0.489362 (-5150 2450);
PAINT SKYBLUE (-5150 2450);
FORCEPROP 1 LAST VALUE 0.1UF
J 0
(-5150 2550);
DISPLAY 0.489362 (-5150 2550);
PAINT SKYBLUE (-5150 2550);
FORCEPROP 1 LAST PART_NUMBER CH4104K1B00
J 0
(-5150 2350);
DISPLAY 0.489362 (-5150 2350);
PAINT SKYBLUE (-5150 2350);
FORCEPROP 1 LAST VOLTAGE 25V
J 0
(-5150 2500);
DISPLAY 0.489362 (-5150 2500);
PAINT SKYBLUE (-5150 2500);
FORCEPROP 1 LAST PACK_TYPE 0402
J 0
(-5150 2300);
DISPLAY 0.489362 (-5150 2300);
PAINT SKYBLUE (-5150 2300);
FORCEPROP 2 LAST CDS_LIB pure_quanta
J 0
(-5200 2500);
DISPLAY INVISIBLE (-5200 2500);
FORCEPROP 1 LAST PATH I108
J 0
(-5150 2650);
DISPLAY 0.978723 (-5150 2650);
PAINT WHITE (-5150 2650);
DISPLAY INVISIBLE (-5150 2650);
FORCEADD Q_CAP..1
(-7450 5250);
FORCEPROP 1 LAST LOCATION PC546
J 0
(-7400 5350);
DISPLAY 0.489362 (-7400 5350);
PAINT SKYBLUE (-7400 5350);
FORCEPROP 0 LAST $SEC 1
J 0
(-7400 5400);
DISPLAY 0.680851 (-7400 5400);
PAINT MONO (-7400 5400);
DISPLAY INVISIBLE (-7400 5400);
FORCEPROP 0 LAST CDS_SEC 1
J 0
(-7400 5400);
DISPLAY 1.021277 (-7400 5400);
DISPLAY INVISIBLE (-7400 5400);
FORCEPROP 1 LASTPIN (-7450 5350) $PN 1
J 0
(-7440 5330);
DISPLAY 0.489362 (-7440 5330);
PAINT MONO (-7440 5330);
FORCEPROP 1 LASTPIN (-7450 5150) $PN 2
J 0
(-7440 5130);
DISPLAY 0.489362 (-7440 5130);
PAINT MONO (-7440 5130);
FORCEPROP 1 LAST MATERIAL X6S
J 0
(-7400 5150);
DISPLAY 0.489362 (-7400 5150);
PAINT SKYBLUE (-7400 5150);
FORCEPROP 1 LAST TOLERANCE 10%
J 0
(-7400 5200);
DISPLAY 0.489362 (-7400 5200);
PAINT SKYBLUE (-7400 5200);
FORCEPROP 1 LAST VALUE 2.2UF
J 0
(-7400 5300);
DISPLAY 0.489362 (-7400 5300);
PAINT SKYBLUE (-7400 5300);
FORCEPROP 1 LAST PART_NUMBER CH5222KEB01
J 0
(-7400 5100);
DISPLAY 0.489362 (-7400 5100);
PAINT SKYBLUE (-7400 5100);
FORCEPROP 1 LAST VOLTAGE 10V
J 0
(-7400 5250);
DISPLAY 0.489362 (-7400 5250);
PAINT SKYBLUE (-7400 5250);
FORCEPROP 1 LAST PACK_TYPE C0402
J 0
(-7400 5050);
DISPLAY 0.489362 (-7400 5050);
PAINT SKYBLUE (-7400 5050);
FORCEPROP 2 LAST CDS_LIB pure_quanta
J 0
(-7450 5250);
DISPLAY INVISIBLE (-7450 5250);
FORCEPROP 1 LAST PATH I109
J 0
(-7400 5400);
DISPLAY 0.978723 (-7400 5400);
PAINT WHITE (-7400 5400);
DISPLAY INVISIBLE (-7400 5400);
FORCEADD UNIVERSAL_GND..1
(-7450 5050);
FORCEPROP 3 LASTPIN (-7450 5100) SIG_NAME GND\g
J 0
(-7440 5110);
DISPLAY 0.659574 (-7440 5110);
PAINT MONO (-7440 5110);
DISPLAY INVISIBLE (-7440 5110);
FORCEPROP 2 LAST CDS_LIB pure_quanta_power
J 0
(-7450 5050);
DISPLAY INVISIBLE (-7450 5050);
FORCEPROP 1 LAST PATH I110
J 0
(-7375 5050);
DISPLAY 0.872340 (-7375 5050);
PAINT AQUA (-7375 5050);
DISPLAY INVISIBLE (-7375 5050);
FORCEPROP 1 LAST HDL_POWER GND
J 1
(-7425 4975);
DISPLAY 0.872340 (-7425 4975);
PAINT GREEN (-7425 4975);
DISPLAY INVISIBLE (-7425 4975);
FORCEADD UNIVERSAL_GND..1
(-7100 5500);
FORCEPROP 3 LASTPIN (-7100 5550) SIG_NAME GND\g
J 0
(-7090 5560);
DISPLAY 0.659574 (-7090 5560);
PAINT MONO (-7090 5560);
DISPLAY INVISIBLE (-7090 5560);
FORCEPROP 2 LAST CDS_LIB pure_quanta_power
J 0
(-7100 5500);
DISPLAY INVISIBLE (-7100 5500);
FORCEPROP 1 LAST PATH I111
J 0
(-7025 5500);
DISPLAY 0.872340 (-7025 5500);
PAINT AQUA (-7025 5500);
DISPLAY INVISIBLE (-7025 5500);
FORCEPROP 1 LAST HDL_POWER GND
J 1
(-7075 5425);
DISPLAY 0.872340 (-7075 5425);
PAINT GREEN (-7075 5425);
DISPLAY INVISIBLE (-7075 5425);
FORCEADD Q_RES..2
(-7450 5750);
FORCEPROP 1 LAST LOCATION PR344
J 0
(-7400 5850);
DISPLAY 0.489362 (-7400 5850);
PAINT SKYBLUE (-7400 5850);
FORCEPROP 0 LAST $SEC 1
J 0
(-7400 5925);
DISPLAY 0.680851 (-7400 5925);
PAINT MONO (-7400 5925);
DISPLAY INVISIBLE (-7400 5925);
FORCEPROP 0 LAST CDS_SEC 1
J 0
(-7400 5925);
DISPLAY 1.021277 (-7400 5925);
DISPLAY INVISIBLE (-7400 5925);
FORCEPROP 1 LASTPIN (-7450 5850) $PN 1
J 0
(-7445 5812);
DISPLAY 0.489362 (-7445 5812);
PAINT MONO (-7445 5812);
FORCEPROP 1 LASTPIN (-7450 5650) $PN 2
J 0
(-7445 5660);
DISPLAY 0.489362 (-7445 5660);
PAINT MONO (-7445 5660);
FORCEPROP 1 LAST WATTAGE 1/16W
J 0
(-7400 5700);
DISPLAY 0.489362 (-7400 5700);
PAINT SKYBLUE (-7400 5700);
FORCEPROP 1 LAST MATERIAL CHIP
J 0
(-7400 5650);
DISPLAY 0.489362 (-7400 5650);
PAINT SKYBLUE (-7400 5650);
FORCEPROP 1 LAST TOLERANCE 1%
J 0
(-7400 5750);
DISPLAY 0.489362 (-7400 5750);
PAINT SKYBLUE (-7400 5750);
FORCEPROP 1 LAST VALUE 2.2
J 0
(-7400 5800);
DISPLAY 0.489362 (-7400 5800);
PAINT SKYBLUE (-7400 5800);
FORCEPROP 1 LAST PART_NUMBER CS-2202FB00
J 0
(-7400 5600);
DISPLAY 0.489362 (-7400 5600);
PAINT SKYBLUE (-7400 5600);
FORCEPROP 1 LAST PACK_TYPE 0402LF
J 0
(-7400 5550);
DISPLAY 0.489362 (-7400 5550);
PAINT SKYBLUE (-7400 5550);
FORCEPROP 2 LAST CDS_LIB pure_quanta
J 0
(-7450 5750);
DISPLAY INVISIBLE (-7450 5750);
FORCEPROP 1 LAST PATH I112
J 0
(-7400 5925);
DISPLAY 0.978723 (-7400 5925);
PAINT WHITE (-7400 5925);
DISPLAY INVISIBLE (-7400 5925);
FORCEADD Q_CAP..1
(-7100 5750);
FORCEPROP 1 LAST LOCATION PC548_C0P0_3
J 0
(-7050 5850);
DISPLAY 0.489362 (-7050 5850);
PAINT SKYBLUE (-7050 5850);
FORCEPROP 0 LAST $SEC 1
J 0
(-7050 5900);
DISPLAY 0.680851 (-7050 5900);
PAINT MONO (-7050 5900);
DISPLAY INVISIBLE (-7050 5900);
FORCEPROP 0 LAST CDS_SEC 1
J 0
(-7050 5900);
DISPLAY 1.021277 (-7050 5900);
DISPLAY INVISIBLE (-7050 5900);
FORCEPROP 1 LASTPIN (-7100 5850) $PN 1
J 0
(-7090 5830);
DISPLAY 0.489362 (-7090 5830);
PAINT MONO (-7090 5830);
FORCEPROP 1 LASTPIN (-7100 5650) $PN 2
J 0
(-7090 5630);
DISPLAY 0.489362 (-7090 5630);
PAINT MONO (-7090 5630);
FORCEPROP 1 LAST MATERIAL X6S
J 0
(-7050 5650);
DISPLAY 0.489362 (-7050 5650);
PAINT SKYBLUE (-7050 5650);
FORCEPROP 1 LAST TOLERANCE 10%
J 0
(-7050 5700);
DISPLAY 0.489362 (-7050 5700);
PAINT SKYBLUE (-7050 5700);
FORCEPROP 1 LAST VALUE 2.2UF
J 0
(-7050 5800);
DISPLAY 0.489362 (-7050 5800);
PAINT SKYBLUE (-7050 5800);
FORCEPROP 1 LAST PART_NUMBER CH5222KEB01
J 0
(-7050 5600);
DISPLAY 0.489362 (-7050 5600);
PAINT SKYBLUE (-7050 5600);
FORCEPROP 1 LAST VOLTAGE 10V
J 0
(-7050 5750);
DISPLAY 0.489362 (-7050 5750);
PAINT SKYBLUE (-7050 5750);
FORCEPROP 1 LAST PACK_TYPE C0402
J 0
(-7050 5550);
DISPLAY 0.489362 (-7050 5550);
PAINT SKYBLUE (-7050 5550);
FORCEPROP 2 LAST CDS_LIB pure_quanta
J 0
(-7100 5750);
DISPLAY INVISIBLE (-7100 5750);
FORCEPROP 1 LAST PATH I113
J 0
(-7050 5900);
DISPLAY 0.978723 (-7050 5900);
PAINT WHITE (-7050 5900);
DISPLAY INVISIBLE (-7050 5900);
FORCEADD Q_CAP..1
(-7350 1950);
FORCEPROP 1 LAST LOCATION PC547
J 0
(-7300 2050);
DISPLAY 0.489362 (-7300 2050);
PAINT SKYBLUE (-7300 2050);
FORCEPROP 0 LAST $SEC 1
J 0
(-7300 2100);
DISPLAY 0.680851 (-7300 2100);
PAINT MONO (-7300 2100);
DISPLAY INVISIBLE (-7300 2100);
FORCEPROP 0 LAST CDS_SEC 1
J 0
(-7300 2100);
DISPLAY 1.021277 (-7300 2100);
DISPLAY INVISIBLE (-7300 2100);
FORCEPROP 1 LASTPIN (-7350 2050) $PN 1
J 0
(-7340 2030);
DISPLAY 0.489362 (-7340 2030);
PAINT MONO (-7340 2030);
FORCEPROP 1 LASTPIN (-7350 1850) $PN 2
J 0
(-7340 1830);
DISPLAY 0.489362 (-7340 1830);
PAINT MONO (-7340 1830);
FORCEPROP 1 LAST MATERIAL X6S
J 0
(-7300 1850);
DISPLAY 0.489362 (-7300 1850);
PAINT SKYBLUE (-7300 1850);
FORCEPROP 1 LAST TOLERANCE 10%
J 0
(-7300 1900);
DISPLAY 0.489362 (-7300 1900);
PAINT SKYBLUE (-7300 1900);
FORCEPROP 1 LAST VALUE 2.2UF
J 0
(-7300 2000);
DISPLAY 0.489362 (-7300 2000);
PAINT SKYBLUE (-7300 2000);
FORCEPROP 1 LAST PART_NUMBER CH5222KEB01
J 0
(-7300 1800);
DISPLAY 0.489362 (-7300 1800);
PAINT SKYBLUE (-7300 1800);
FORCEPROP 1 LAST VOLTAGE 10V
J 0
(-7300 1950);
DISPLAY 0.489362 (-7300 1950);
PAINT SKYBLUE (-7300 1950);
FORCEPROP 1 LAST PACK_TYPE C0402
J 0
(-7300 1750);
DISPLAY 0.489362 (-7300 1750);
PAINT SKYBLUE (-7300 1750);
FORCEPROP 2 LAST CDS_LIB pure_quanta
J 0
(-7350 1950);
DISPLAY INVISIBLE (-7350 1950);
FORCEPROP 1 LAST PATH I115
J 0
(-7300 2100);
DISPLAY 0.978723 (-7300 2100);
PAINT WHITE (-7300 2100);
DISPLAY INVISIBLE (-7300 2100);
FORCEADD UNIVERSAL_GND..1
(-7350 1750);
FORCEPROP 3 LASTPIN (-7350 1800) SIG_NAME GND\g
J 0
(-7340 1810);
DISPLAY 0.659574 (-7340 1810);
PAINT MONO (-7340 1810);
DISPLAY INVISIBLE (-7340 1810);
FORCEPROP 2 LAST CDS_LIB pure_quanta_power
J 0
(-7350 1750);
DISPLAY INVISIBLE (-7350 1750);
FORCEPROP 1 LAST PATH I116
J 0
(-7275 1750);
DISPLAY 0.872340 (-7275 1750);
PAINT AQUA (-7275 1750);
DISPLAY INVISIBLE (-7275 1750);
FORCEPROP 1 LAST HDL_POWER GND
J 1
(-7325 1675);
DISPLAY 0.872340 (-7325 1675);
PAINT GREEN (-7325 1675);
DISPLAY INVISIBLE (-7325 1675);
FORCEADD UNIVERSAL_GND..1
(-7000 2250);
FORCEPROP 3 LASTPIN (-7000 2300) SIG_NAME GND\g
J 0
(-6990 2310);
DISPLAY 0.659574 (-6990 2310);
PAINT MONO (-6990 2310);
DISPLAY INVISIBLE (-6990 2310);
FORCEPROP 2 LAST CDS_LIB pure_quanta_power
J 0
(-7000 2250);
DISPLAY INVISIBLE (-7000 2250);
FORCEPROP 1 LAST PATH I117
J 0
(-6925 2250);
DISPLAY 0.872340 (-6925 2250);
PAINT AQUA (-6925 2250);
DISPLAY INVISIBLE (-6925 2250);
FORCEPROP 1 LAST HDL_POWER GND
J 1
(-6975 2175);
DISPLAY 0.872340 (-6975 2175);
PAINT GREEN (-6975 2175);
DISPLAY INVISIBLE (-6975 2175);
FORCEADD Q_RES..2
(-7350 2500);
FORCEPROP 1 LAST LOCATION PR345
J 0
(-7305 2625);
DISPLAY 0.489362 (-7305 2625);
PAINT SKYBLUE (-7305 2625);
FORCEPROP 0 LAST $SEC 1
J 0
(-7300 2675);
DISPLAY 0.680851 (-7300 2675);
PAINT MONO (-7300 2675);
DISPLAY INVISIBLE (-7300 2675);
FORCEPROP 0 LAST CDS_SEC 1
J 0
(-7300 2675);
DISPLAY 1.021277 (-7300 2675);
DISPLAY INVISIBLE (-7300 2675);
FORCEPROP 1 LASTPIN (-7350 2600) $PN 1
J 0
(-7345 2562);
DISPLAY 0.489362 (-7345 2562);
PAINT MONO (-7345 2562);
FORCEPROP 1 LASTPIN (-7350 2400) $PN 2
J 0
(-7345 2410);
DISPLAY 0.489362 (-7345 2410);
PAINT MONO (-7345 2410);
FORCEPROP 1 LAST WATTAGE 1/16W
J 0
(-7300 2475);
DISPLAY 0.489362 (-7300 2475);
PAINT SKYBLUE (-7300 2475);
FORCEPROP 1 LAST MATERIAL CHIP
J 0
(-7300 2425);
DISPLAY 0.489362 (-7300 2425);
PAINT SKYBLUE (-7300 2425);
FORCEPROP 1 LAST TOLERANCE 1%
J 0
(-7300 2525);
DISPLAY 0.489362 (-7300 2525);
PAINT SKYBLUE (-7300 2525);
FORCEPROP 1 LAST VALUE 2.2
J 0
(-7300 2575);
DISPLAY 0.489362 (-7300 2575);
PAINT SKYBLUE (-7300 2575);
FORCEPROP 1 LAST PART_NUMBER CS-2202FB00
J 0
(-7300 2375);
DISPLAY 0.489362 (-7300 2375);
PAINT SKYBLUE (-7300 2375);
FORCEPROP 1 LAST PACK_TYPE 0402LF
J 0
(-7300 2325);
DISPLAY 0.489362 (-7300 2325);
PAINT SKYBLUE (-7300 2325);
FORCEPROP 2 LAST CDS_LIB pure_quanta
J 0
(-7350 2500);
DISPLAY INVISIBLE (-7350 2500);
FORCEPROP 1 LAST PATH I118
J 0
(-7300 2675);
DISPLAY 0.978723 (-7300 2675);
PAINT WHITE (-7300 2675);
DISPLAY INVISIBLE (-7300 2675);
FORCEADD Q_CAP..1
(-7000 2525);
FORCEPROP 1 LAST LOCATION PC549_C0P0_4
J 0
(-6950 2625);
DISPLAY 0.489362 (-6950 2625);
PAINT SKYBLUE (-6950 2625);
FORCEPROP 0 LAST $SEC 1
J 0
(-6950 2675);
DISPLAY 0.680851 (-6950 2675);
PAINT MONO (-6950 2675);
DISPLAY INVISIBLE (-6950 2675);
FORCEPROP 0 LAST CDS_SEC 1
J 0
(-6950 2675);
DISPLAY 1.021277 (-6950 2675);
DISPLAY INVISIBLE (-6950 2675);
FORCEPROP 1 LASTPIN (-7000 2625) $PN 1
J 0
(-6990 2605);
DISPLAY 0.489362 (-6990 2605);
PAINT MONO (-6990 2605);
FORCEPROP 1 LASTPIN (-7000 2425) $PN 2
J 0
(-6990 2405);
DISPLAY 0.489362 (-6990 2405);
PAINT MONO (-6990 2405);
FORCEPROP 1 LAST MATERIAL X6S
J 0
(-6950 2425);
DISPLAY 0.489362 (-6950 2425);
PAINT SKYBLUE (-6950 2425);
FORCEPROP 1 LAST TOLERANCE 10%
J 0
(-6950 2475);
DISPLAY 0.489362 (-6950 2475);
PAINT SKYBLUE (-6950 2475);
FORCEPROP 1 LAST VALUE 2.2UF
J 0
(-6950 2575);
DISPLAY 0.489362 (-6950 2575);
PAINT SKYBLUE (-6950 2575);
FORCEPROP 1 LAST PART_NUMBER CH5222KEB01
J 0
(-6950 2375);
DISPLAY 0.489362 (-6950 2375);
PAINT SKYBLUE (-6950 2375);
FORCEPROP 1 LAST VOLTAGE 10V
J 0
(-6950 2525);
DISPLAY 0.489362 (-6950 2525);
PAINT SKYBLUE (-6950 2525);
FORCEPROP 1 LAST PACK_TYPE C0402
J 0
(-6950 2325);
DISPLAY 0.489362 (-6950 2325);
PAINT SKYBLUE (-6950 2325);
FORCEPROP 2 LAST CDS_LIB pure_quanta
J 0
(-7000 2525);
DISPLAY INVISIBLE (-7000 2525);
FORCEPROP 1 LAST PATH I119
J 0
(-6950 2675);
DISPLAY 0.978723 (-6950 2675);
PAINT WHITE (-6950 2675);
DISPLAY INVISIBLE (-6950 2675);
FORCEADD ISL99390FRZTR5935..1
(-5950 4900);
FORCEPROP 1 LAST LOCATION PU46
J 0
(-6250 5775);
DISPLAY 0.489362 (-6250 5775);
PAINT SKYBLUE (-6250 5775);
FORCEPROP 0 LAST $SEC 1
J 0
(-6250 5925);
DISPLAY 0.680851 (-6250 5925);
PAINT MONO (-6250 5925);
DISPLAY INVISIBLE (-6250 5925);
FORCEPROP 0 LAST CDS_SEC 1
J 0
(-6250 5925);
DISPLAY 1.021277 (-6250 5925);
DISPLAY INVISIBLE (-6250 5925);
FORCEPROP 0 LASTPIN (-5550 4450) $PN 2
J 0
(-5540 4460);
DISPLAY 0.489362 (-5540 4460);
PAINT MONO (-5540 4460);
FORCEPROP 0 LASTPIN (-5550 5250) $PN 33
J 0
(-5540 5260);
DISPLAY 0.489362 (-5540 5260);
PAINT MONO (-5540 5260);
FORCEPROP 0 LASTPIN (-6400 4650) $PN 31
J 2
(-6410 4660);
DISPLAY 0.489362 (-6410 4660);
PAINT MONO (-6410 4660);
FORCEPROP 0 LASTPIN (-6400 5050) $PN 35
J 2
(-6410 5060);
DISPLAY 0.489362 (-6410 5060);
PAINT MONO (-6410 5060);
FORCEPROP 0 LASTPIN (-5550 4600) $PN 6
J 0
(-5540 4610);
DISPLAY 0.489362 (-5540 4610);
PAINT MONO (-5540 4610);
FORCEPROP 0 LASTPIN (-5550 4550) $PN 41
J 0
(-5540 4560);
DISPLAY 0.489362 (-5540 4560);
PAINT MONO (-5540 4560);
FORCEPROP 0 LASTPIN (-6400 4900) $PN 38
J 2
(-6410 4910);
DISPLAY 0.489362 (-6410 4910);
PAINT MONO (-6410 4910);
FORCEPROP 0 LASTPIN (-6400 4600) $PN 37
J 2
(-6410 4610);
DISPLAY 0.489362 (-6410 4610);
PAINT MONO (-6410 4610);
FORCEPROP 0 LASTPIN (-5550 4400) $PN 5
J 0
(-5540 4410);
DISPLAY 0.489362 (-5540 4410);
PAINT MONO (-5540 4410);
FORCEPROP 0 LASTPIN (-5550 4350) $PN 7_9-20_24
J 0
(-5540 4360);
DISPLAY 0.489362 (-5540 4360);
PAINT MONO (-5540 4360);
FORCEPROP 0 LASTPIN (-5550 4300) $PN 40
J 0
(-5540 4310);
DISPLAY 0.489362 (-5540 4310);
PAINT MONO (-5540 4310);
FORCEPROP 0 LASTPIN (-5550 5000) $PN 32
J 0
(-5540 5010);
DISPLAY 0.489362 (-5540 5010);
PAINT MONO (-5540 5010);
FORCEPROP 0 LASTPIN (-6400 5550) $PN 4
J 2
(-6410 5560);
DISPLAY 0.489362 (-6410 5560);
PAINT MONO (-6410 5560);
FORCEPROP 0 LASTPIN (-6400 4300) $PN 34
J 2
(-6410 4310);
DISPLAY 0.489362 (-6410 4310);
PAINT MONO (-6410 4310);
FORCEPROP 0 LASTPIN (-6400 4800) $PN 39
J 2
(-6410 4810);
DISPLAY 0.489362 (-6410 4810);
PAINT MONO (-6410 4810);
FORCEPROP 0 LASTPIN (-5550 4900) $PN 10_19
J 0
(-5540 4910);
DISPLAY 0.489362 (-5540 4910);
PAINT MONO (-5540 4910);
FORCEPROP 0 LASTPIN (-6400 4400) $PN 36
J 2
(-6410 4410);
DISPLAY 0.489362 (-6410 4410);
PAINT MONO (-6410 4410);
FORCEPROP 0 LASTPIN (-6400 5250) $PN 3
J 2
(-6410 5260);
DISPLAY 0.489362 (-6410 5260);
PAINT MONO (-6410 5260);
FORCEPROP 0 LASTPIN (-5550 5550) $PN 25_29
J 0
(-5540 5560);
DISPLAY 0.489362 (-5540 5560);
PAINT MONO (-5540 5560);
FORCEPROP 0 LASTPIN (-5550 5500) $PN 30
J 0
(-5540 5510);
DISPLAY 0.489362 (-5540 5510);
PAINT MONO (-5540 5510);
FORCEPROP 0 LASTPIN (-5550 4650) $PN 1
J 0
(-5540 4660);
DISPLAY 0.489362 (-5540 4660);
PAINT MONO (-5540 4660);
FORCEPROP 2 LAST PART_TYPE SMLF
J 0
(-6250 5875);
DISPLAY 1.021277 (-6250 5875);
FORCEPROP 1 LAST MATERIAL IC
J 0
(-6250 5625);
DISPLAY 0.489362 (-6250 5625);
PAINT SKYBLUE (-6250 5625);
FORCEPROP 2 LAST VALUE ISL99390FRZ-TR5935
J 0
(-6250 5825);
DISPLAY 0.489362 (-6250 5825);
PAINT SKYBLUE (-6250 5825);
FORCEPROP 1 LAST PART_NUMBER AL099390004
J 0
(-6250 5700);
DISPLAY 0.489362 (-6250 5700);
PAINT SKYBLUE (-6250 5700);
FORCEPROP 2 LAST CDS_LIB pure_quanta
J 0
(-5950 4900);
DISPLAY INVISIBLE (-5950 4900);
FORCEPROP 1 LAST NEEDS_NO_SIZE TRUE
J 0
(-5950 4900);
DISPLAY 0.723404 (-5950 4900);
PAINT GREEN (-5950 4900);
DISPLAY INVISIBLE (-5950 4900);
FORCEPROP 1 LAST CDS_LMAN_SYM_OUTLINE -300,700,250,-650
J 0
(-5950 4900);
DISPLAY 0.468085 (-5950 4900);
PAINT GREEN (-5950 4900);
DISPLAY INVISIBLE (-5950 4900);
FORCEPROP 1 LAST PATH I121
J 0
(-5950 4900);
DISPLAY 0.723404 (-5950 4900);
PAINT GREEN (-5950 4900);
DISPLAY INVISIBLE (-5950 4900);
FORCEADD ISL99390FRZTR5935..1
(-5875 1600);
FORCEPROP 1 LAST LOCATION PU47
J 0
(-6175 2475);
DISPLAY 0.489362 (-6175 2475);
PAINT SKYBLUE (-6175 2475);
FORCEPROP 0 LAST $SEC 1
J 0
(-6175 2625);
DISPLAY 0.680851 (-6175 2625);
PAINT MONO (-6175 2625);
DISPLAY INVISIBLE (-6175 2625);
FORCEPROP 0 LAST CDS_SEC 1
J 0
(-6175 2625);
DISPLAY 1.021277 (-6175 2625);
DISPLAY INVISIBLE (-6175 2625);
FORCEPROP 0 LASTPIN (-5475 1150) $PN 2
J 0
(-5465 1160);
DISPLAY 0.489362 (-5465 1160);
PAINT MONO (-5465 1160);
FORCEPROP 0 LASTPIN (-5475 1950) $PN 33
J 0
(-5465 1960);
DISPLAY 0.489362 (-5465 1960);
PAINT MONO (-5465 1960);
FORCEPROP 0 LASTPIN (-6325 1350) $PN 31
J 2
(-6335 1360);
DISPLAY 0.489362 (-6335 1360);
PAINT MONO (-6335 1360);
FORCEPROP 0 LASTPIN (-6325 1750) $PN 35
J 2
(-6335 1760);
DISPLAY 0.489362 (-6335 1760);
PAINT MONO (-6335 1760);
FORCEPROP 0 LASTPIN (-5475 1300) $PN 6
J 0
(-5465 1310);
DISPLAY 0.489362 (-5465 1310);
PAINT MONO (-5465 1310);
FORCEPROP 0 LASTPIN (-5475 1250) $PN 41
J 0
(-5465 1260);
DISPLAY 0.489362 (-5465 1260);
PAINT MONO (-5465 1260);
FORCEPROP 0 LASTPIN (-6325 1600) $PN 38
J 2
(-6335 1610);
DISPLAY 0.489362 (-6335 1610);
PAINT MONO (-6335 1610);
FORCEPROP 0 LASTPIN (-6325 1300) $PN 37
J 2
(-6335 1310);
DISPLAY 0.489362 (-6335 1310);
PAINT MONO (-6335 1310);
FORCEPROP 0 LASTPIN (-5475 1100) $PN 5
J 0
(-5465 1110);
DISPLAY 0.489362 (-5465 1110);
PAINT MONO (-5465 1110);
FORCEPROP 0 LASTPIN (-5475 1050) $PN 7_9-20_24
J 0
(-5465 1060);
DISPLAY 0.489362 (-5465 1060);
PAINT MONO (-5465 1060);
FORCEPROP 0 LASTPIN (-5475 1000) $PN 40
J 0
(-5465 1010);
DISPLAY 0.489362 (-5465 1010);
PAINT MONO (-5465 1010);
FORCEPROP 0 LASTPIN (-5475 1700) $PN 32
J 0
(-5465 1710);
DISPLAY 0.489362 (-5465 1710);
PAINT MONO (-5465 1710);
FORCEPROP 0 LASTPIN (-6325 2250) $PN 4
J 2
(-6335 2260);
DISPLAY 0.489362 (-6335 2260);
PAINT MONO (-6335 2260);
FORCEPROP 0 LASTPIN (-6325 1000) $PN 34
J 2
(-6335 1010);
DISPLAY 0.489362 (-6335 1010);
PAINT MONO (-6335 1010);
FORCEPROP 0 LASTPIN (-6325 1500) $PN 39
J 2
(-6335 1510);
DISPLAY 0.489362 (-6335 1510);
PAINT MONO (-6335 1510);
FORCEPROP 0 LASTPIN (-5475 1600) $PN 10_19
J 0
(-5465 1610);
DISPLAY 0.489362 (-5465 1610);
PAINT MONO (-5465 1610);
FORCEPROP 0 LASTPIN (-6325 1100) $PN 36
J 2
(-6335 1110);
DISPLAY 0.489362 (-6335 1110);
PAINT MONO (-6335 1110);
FORCEPROP 0 LASTPIN (-6325 1950) $PN 3
J 2
(-6335 1960);
DISPLAY 0.489362 (-6335 1960);
PAINT MONO (-6335 1960);
FORCEPROP 0 LASTPIN (-5475 2250) $PN 25_29
J 0
(-5465 2260);
DISPLAY 0.489362 (-5465 2260);
PAINT MONO (-5465 2260);
FORCEPROP 0 LASTPIN (-5475 2200) $PN 30
J 0
(-5465 2210);
DISPLAY 0.489362 (-5465 2210);
PAINT MONO (-5465 2210);
FORCEPROP 0 LASTPIN (-5475 1350) $PN 1
J 0
(-5465 1360);
DISPLAY 0.489362 (-5465 1360);
PAINT MONO (-5465 1360);
FORCEPROP 2 LAST PART_TYPE SMLF
J 0
(-6175 2575);
DISPLAY 1.021277 (-6175 2575);
FORCEPROP 1 LAST MATERIAL IC
J 0
(-6175 2325);
DISPLAY 0.489362 (-6175 2325);
PAINT SKYBLUE (-6175 2325);
FORCEPROP 2 LAST VALUE ISL99390FRZ-TR5935
J 0
(-6175 2525);
DISPLAY 0.489362 (-6175 2525);
PAINT SKYBLUE (-6175 2525);
FORCEPROP 1 LAST PART_NUMBER AL099390004
J 0
(-6175 2400);
DISPLAY 0.489362 (-6175 2400);
PAINT SKYBLUE (-6175 2400);
FORCEPROP 2 LAST CDS_LIB pure_quanta
J 0
(-5875 1600);
DISPLAY INVISIBLE (-5875 1600);
FORCEPROP 1 LAST NEEDS_NO_SIZE TRUE
J 0
(-5875 1600);
DISPLAY 0.723404 (-5875 1600);
PAINT GREEN (-5875 1600);
DISPLAY INVISIBLE (-5875 1600);
FORCEPROP 1 LAST CDS_LMAN_SYM_OUTLINE -300,700,250,-650
J 0
(-5875 1600);
DISPLAY 0.468085 (-5875 1600);
PAINT GREEN (-5875 1600);
DISPLAY INVISIBLE (-5875 1600);
FORCEPROP 1 LAST PATH I122
J 0
(-5875 1600);
DISPLAY 0.723404 (-5875 1600);
PAINT GREEN (-5875 1600);
DISPLAY INVISIBLE (-5875 1600);
FORCEADD Q_CAP..1
(-4475 4725);
FORCEPROP 1 LAST LOCATION PC180
J 0
(-4425 4825);
DISPLAY 0.489362 (-4425 4825);
PAINT SKYBLUE (-4425 4825);
FORCEPROP 0 LAST $SEC 1
J 0
(-4425 4875);
DISPLAY 0.680851 (-4425 4875);
PAINT MONO (-4425 4875);
DISPLAY INVISIBLE (-4425 4875);
FORCEPROP 0 LAST CDS_SEC 1
J 0
(-4425 4875);
DISPLAY 1.021277 (-4425 4875);
DISPLAY INVISIBLE (-4425 4875);
FORCEPROP 1 LASTPIN (-4475 4825) $PN 1
J 0
(-4465 4805);
DISPLAY 0.489362 (-4465 4805);
PAINT MONO (-4465 4805);
FORCEPROP 1 LASTPIN (-4475 4625) $PN 2
J 0
(-4465 4605);
DISPLAY 0.489362 (-4465 4605);
PAINT MONO (-4465 4605);
FORCEPROP 1 LAST MATERIAL EMPTY
J 0
(-4425 4625);
DISPLAY 0.489362 (-4425 4625);
PAINT RED (-4425 4625);
FORCEPROP 1 LAST TOLERANCE 10%
J 0
(-4425 4675);
DISPLAY 0.489362 (-4425 4675);
PAINT SKYBLUE (-4425 4675);
FORCEPROP 1 LAST VALUE 560PF
J 0
(-4425 4775);
DISPLAY 0.489362 (-4425 4775);
PAINT SKYBLUE (-4425 4775);
FORCEPROP 1 LAST PART_NUMBER CH1566K1B09
J 0
(-4425 4575);
DISPLAY 0.489362 (-4425 4575);
PAINT SKYBLUE (-4425 4575);
FORCEPROP 1 LAST VOLTAGE 50V
J 0
(-4425 4725);
DISPLAY 0.489362 (-4425 4725);
PAINT SKYBLUE (-4425 4725);
FORCEPROP 1 LAST PACK_TYPE C0402
J 0
(-4425 4525);
DISPLAY 0.489362 (-4425 4525);
PAINT SKYBLUE (-4425 4525);
FORCEPROP 2 LAST CDS_LIB pure_quanta
J 0
(-4475 4725);
DISPLAY INVISIBLE (-4475 4725);
FORCEPROP 1 LAST PATH I123
J 0
(-4425 4875);
DISPLAY 0.978723 (-4425 4875);
PAINT WHITE (-4425 4875);
DISPLAY INVISIBLE (-4425 4875);
FORCEADD Q_RES..2
(-4475 4250);
FORCEPROP 1 LAST LOCATION PR498
J 0
(-4430 4375);
DISPLAY 0.489362 (-4430 4375);
PAINT SKYBLUE (-4430 4375);
FORCEPROP 0 LAST $SEC 1
J 0
(-4425 4425);
DISPLAY 0.680851 (-4425 4425);
PAINT MONO (-4425 4425);
DISPLAY INVISIBLE (-4425 4425);
FORCEPROP 0 LAST CDS_SEC 1
J 0
(-4425 4425);
DISPLAY 1.021277 (-4425 4425);
DISPLAY INVISIBLE (-4425 4425);
FORCEPROP 1 LASTPIN (-4475 4350) $PN 1
J 0
(-4470 4312);
DISPLAY 0.489362 (-4470 4312);
PAINT MONO (-4470 4312);
FORCEPROP 1 LASTPIN (-4475 4150) $PN 2
J 0
(-4470 4160);
DISPLAY 0.489362 (-4470 4160);
PAINT MONO (-4470 4160);
FORCEPROP 1 LAST WATTAGE 1/8W
J 0
(-4435 4225);
DISPLAY 0.489362 (-4435 4225);
PAINT SKYBLUE (-4435 4225);
FORCEPROP 1 LAST MATERIAL EMPTY
J 0
(-4435 4175);
DISPLAY 0.489362 (-4435 4175);
PAINT RED (-4435 4175);
FORCEPROP 1 LAST TOLERANCE 1%
J 0
(-4430 4275);
DISPLAY 0.489362 (-4430 4275);
PAINT SKYBLUE (-4430 4275);
FORCEPROP 1 LAST VALUE 1.5
J 0
(-4430 4325);
DISPLAY 0.489362 (-4430 4325);
PAINT SKYBLUE (-4430 4325);
FORCEPROP 1 LAST PART_NUMBER CS-1504FB00
J 0
(-4435 4125);
DISPLAY 0.489362 (-4435 4125);
PAINT SKYBLUE (-4435 4125);
FORCEPROP 1 LAST PACK_TYPE 0402LF
J 0
(-4435 4075);
DISPLAY 0.489362 (-4435 4075);
PAINT SKYBLUE (-4435 4075);
FORCEPROP 2 LAST CDS_LIB pure_quanta
J 0
(-4475 4250);
DISPLAY INVISIBLE (-4475 4250);
FORCEPROP 1 LAST PATH I124
J 0
(-4425 4425);
DISPLAY 0.978723 (-4425 4425);
PAINT WHITE (-4425 4425);
DISPLAY INVISIBLE (-4425 4425);
FORCEADD UNIVERSAL_GND..1
(-4475 4025);
FORCEPROP 3 LASTPIN (-4475 4075) SIG_NAME GND\g
J 0
(-4465 4085);
DISPLAY 0.659574 (-4465 4085);
PAINT MONO (-4465 4085);
DISPLAY INVISIBLE (-4465 4085);
FORCEPROP 2 LAST CDS_LIB pure_quanta_power
J 0
(-4475 4025);
DISPLAY INVISIBLE (-4475 4025);
FORCEPROP 1 LAST PATH I125
J 0
(-4400 4025);
DISPLAY 0.872340 (-4400 4025);
PAINT AQUA (-4400 4025);
DISPLAY INVISIBLE (-4400 4025);
FORCEPROP 1 LAST HDL_POWER GND
J 1
(-4450 3950);
DISPLAY 0.872340 (-4450 3950);
PAINT GREEN (-4450 3950);
DISPLAY INVISIBLE (-4450 3950);
FORCEADD Q_CAP..1
(-4400 1425);
FORCEPROP 1 LAST LOCATION PC181
J 0
(-4350 1525);
DISPLAY 0.489362 (-4350 1525);
PAINT SKYBLUE (-4350 1525);
FORCEPROP 0 LAST $SEC 1
J 0
(-4350 1575);
DISPLAY 0.680851 (-4350 1575);
PAINT MONO (-4350 1575);
DISPLAY INVISIBLE (-4350 1575);
FORCEPROP 0 LAST CDS_SEC 1
J 0
(-4350 1575);
DISPLAY 1.021277 (-4350 1575);
DISPLAY INVISIBLE (-4350 1575);
FORCEPROP 1 LASTPIN (-4400 1525) $PN 1
J 0
(-4390 1505);
DISPLAY 0.489362 (-4390 1505);
PAINT MONO (-4390 1505);
FORCEPROP 1 LASTPIN (-4400 1325) $PN 2
J 0
(-4390 1305);
DISPLAY 0.489362 (-4390 1305);
PAINT MONO (-4390 1305);
FORCEPROP 1 LAST MATERIAL EMPTY
J 0
(-4350 1325);
DISPLAY 0.489362 (-4350 1325);
PAINT RED (-4350 1325);
FORCEPROP 1 LAST TOLERANCE 10%
J 0
(-4350 1375);
DISPLAY 0.489362 (-4350 1375);
PAINT SKYBLUE (-4350 1375);
FORCEPROP 1 LAST VALUE 560PF
J 0
(-4350 1475);
DISPLAY 0.489362 (-4350 1475);
PAINT SKYBLUE (-4350 1475);
FORCEPROP 1 LAST PART_NUMBER CH1566K1B09
J 0
(-4350 1275);
DISPLAY 0.489362 (-4350 1275);
PAINT SKYBLUE (-4350 1275);
FORCEPROP 1 LAST VOLTAGE 50V
J 0
(-4350 1425);
DISPLAY 0.489362 (-4350 1425);
PAINT SKYBLUE (-4350 1425);
FORCEPROP 1 LAST PACK_TYPE C0402
J 0
(-4350 1225);
DISPLAY 0.489362 (-4350 1225);
PAINT SKYBLUE (-4350 1225);
FORCEPROP 2 LAST CDS_LIB pure_quanta
J 0
(-4400 1425);
DISPLAY INVISIBLE (-4400 1425);
FORCEPROP 1 LAST PATH I126
J 0
(-4350 1575);
DISPLAY 0.978723 (-4350 1575);
PAINT WHITE (-4350 1575);
DISPLAY INVISIBLE (-4350 1575);
FORCEADD Q_RES..2
(-4400 975);
FORCEPROP 1 LAST LOCATION PR499
J 0
(-4355 1100);
DISPLAY 0.489362 (-4355 1100);
PAINT SKYBLUE (-4355 1100);
FORCEPROP 0 LAST $SEC 1
J 0
(-4350 1150);
DISPLAY 0.680851 (-4350 1150);
PAINT MONO (-4350 1150);
DISPLAY INVISIBLE (-4350 1150);
FORCEPROP 0 LAST CDS_SEC 1
J 0
(-4350 1150);
DISPLAY 1.021277 (-4350 1150);
DISPLAY INVISIBLE (-4350 1150);
FORCEPROP 1 LASTPIN (-4400 1075) $PN 1
J 0
(-4395 1037);
DISPLAY 0.489362 (-4395 1037);
PAINT MONO (-4395 1037);
FORCEPROP 1 LASTPIN (-4400 875) $PN 2
J 0
(-4395 885);
DISPLAY 0.489362 (-4395 885);
PAINT MONO (-4395 885);
FORCEPROP 1 LAST WATTAGE 1/8W
J 0
(-4360 950);
DISPLAY 0.489362 (-4360 950);
PAINT SKYBLUE (-4360 950);
FORCEPROP 1 LAST MATERIAL EMPTY
J 0
(-4360 900);
DISPLAY 0.489362 (-4360 900);
PAINT RED (-4360 900);
FORCEPROP 1 LAST TOLERANCE 1%
J 0
(-4355 1000);
DISPLAY 0.489362 (-4355 1000);
PAINT SKYBLUE (-4355 1000);
FORCEPROP 1 LAST VALUE 1.5
J 0
(-4355 1050);
DISPLAY 0.489362 (-4355 1050);
PAINT SKYBLUE (-4355 1050);
FORCEPROP 1 LAST PART_NUMBER CS-1504FB00
J 0
(-4360 850);
DISPLAY 0.489362 (-4360 850);
PAINT SKYBLUE (-4360 850);
FORCEPROP 1 LAST PACK_TYPE 0402LF
J 0
(-4360 800);
DISPLAY 0.489362 (-4360 800);
PAINT SKYBLUE (-4360 800);
FORCEPROP 2 LAST CDS_LIB pure_quanta
J 0
(-4400 975);
DISPLAY INVISIBLE (-4400 975);
FORCEPROP 1 LAST PATH I127
J 0
(-4350 1150);
DISPLAY 0.978723 (-4350 1150);
PAINT WHITE (-4350 1150);
DISPLAY INVISIBLE (-4350 1150);
FORCEADD UNIVERSAL_GND..1
(-4400 750);
FORCEPROP 3 LASTPIN (-4400 800) SIG_NAME GND\g
J 0
(-4390 810);
DISPLAY 0.659574 (-4390 810);
PAINT MONO (-4390 810);
DISPLAY INVISIBLE (-4390 810);
FORCEPROP 2 LAST CDS_LIB pure_quanta_power
J 0
(-4400 750);
DISPLAY INVISIBLE (-4400 750);
FORCEPROP 1 LAST PATH I128
J 0
(-4325 750);
DISPLAY 0.872340 (-4325 750);
PAINT AQUA (-4325 750);
DISPLAY INVISIBLE (-4325 750);
FORCEPROP 1 LAST HDL_POWER GND
J 1
(-4375 675);
DISPLAY 0.872340 (-4375 675);
PAINT GREEN (-4375 675);
DISPLAY INVISIBLE (-4375 675);
FORCEADD UNIVERSAL_GND..1
(-1975 1150);
FORCEPROP 3 LASTPIN (-1975 1200) SIG_NAME GND\g
J 0
(-1965 1210);
DISPLAY 0.659574 (-1965 1210);
PAINT MONO (-1965 1210);
DISPLAY INVISIBLE (-1965 1210);
FORCEPROP 2 LAST CDS_LIB pure_quanta_power
J 0
(-1975 1150);
DISPLAY INVISIBLE (-1975 1150);
FORCEPROP 1 LAST PATH I129
J 0
(-1900 1150);
DISPLAY 0.872340 (-1900 1150);
PAINT AQUA (-1900 1150);
DISPLAY INVISIBLE (-1900 1150);
FORCEPROP 1 LAST HDL_POWER GND
J 1
(-1950 1075);
DISPLAY 0.872340 (-1950 1075);
PAINT GREEN (-1950 1075);
DISPLAY INVISIBLE (-1950 1075);
FORCEADD VCC_CORE..1
(-7450 6200);
FORCEPROP 3 LASTPIN (-7450 6150) SIG_NAME PVDDCR_CPU0_P0_PVCC\g
J 0
(-7440 6160);
DISPLAY 0.659574 (-7440 6160);
PAINT MONO (-7440 6160);
DISPLAY INVISIBLE (-7440 6160);
FORCEPROP 1 LAST HDL_POWER PVDDCR_CPU0_P0_PVCC
J 1
(-7450 6250);
DISPLAY 0.489362 (-7450 6250);
PAINT GREEN (-7450 6250);
FORCEPROP 2 LAST CDS_LIB pure_quanta_power
J 0
(-7450 6200);
DISPLAY INVISIBLE (-7450 6200);
FORCEPROP 1 LAST PATH I130
J 0
(-7400 6225);
DISPLAY 0.872340 (-7400 6225);
PAINT AQUA (-7400 6225);
DISPLAY INVISIBLE (-7400 6225);
FORCEADD VCC_CORE..1
(-7350 2900);
FORCEPROP 3 LASTPIN (-7350 2850) SIG_NAME PVDDCR_CPU0_P0_PVCC\g
J 0
(-7340 2860);
DISPLAY 0.659574 (-7340 2860);
PAINT MONO (-7340 2860);
DISPLAY INVISIBLE (-7340 2860);
FORCEPROP 1 LAST HDL_POWER PVDDCR_CPU0_P0_PVCC
J 1
(-7350 2950);
DISPLAY 0.489362 (-7350 2950);
PAINT GREEN (-7350 2950);
FORCEPROP 2 LAST CDS_LIB pure_quanta_power
J 0
(-7350 2900);
DISPLAY INVISIBLE (-7350 2900);
FORCEPROP 1 LAST PATH I131
J 0
(-7300 2925);
DISPLAY 0.872340 (-7300 2925);
PAINT AQUA (-7300 2925);
DISPLAY INVISIBLE (-7300 2925);
FORCEADD UNIVERSAL_GND..1
(-5400 4125);
FORCEPROP 3 LASTPIN (-5400 4175) SIG_NAME GND\g
J 0
(-5390 4185);
DISPLAY 0.659574 (-5390 4185);
PAINT MONO (-5390 4185);
DISPLAY INVISIBLE (-5390 4185);
FORCEPROP 2 LAST CDS_LIB pure_quanta_power
J 0
(-5400 4125);
DISPLAY INVISIBLE (-5400 4125);
FORCEPROP 1 LAST PATH I15
J 0
(-5325 4125);
DISPLAY 0.872340 (-5325 4125);
PAINT AQUA (-5325 4125);
DISPLAY INVISIBLE (-5325 4125);
FORCEPROP 1 LAST HDL_POWER GND
J 1
(-5375 4050);
DISPLAY 0.872340 (-5375 4050);
PAINT GREEN (-5375 4050);
DISPLAY INVISIBLE (-5375 4050);
FORCEADD Q_RES..1
(-4150 3950);
FORCEPROP 1 LAST LOCATION PR350
J 0
(-4175 4000);
DISPLAY 0.489362 (-4175 4000);
PAINT SKYBLUE (-4175 4000);
FORCEPROP 0 LAST $SEC 1
J 0
(-4150 4025);
DISPLAY 0.680851 (-4150 4025);
PAINT MONO (-4150 4025);
DISPLAY INVISIBLE (-4150 4025);
FORCEPROP 0 LAST CDS_SEC 1
J 0
(-4150 4025);
DISPLAY 1.021277 (-4150 4025);
DISPLAY INVISIBLE (-4150 4025);
FORCEPROP 1 LASTPIN (-4250 3950) $PN 1
J 0
(-4238 3962);
DISPLAY 0.489362 (-4238 3962);
PAINT MONO (-4238 3962);
FORCEPROP 1 LASTPIN (-4050 3950) $PN 2
J 0
(-4088 3962);
DISPLAY 0.489362 (-4088 3962);
PAINT MONO (-4088 3962);
FORCEPROP 1 LAST WATTAGE 1/16W
J 0
(-4050 3900);
DISPLAY 0.489362 (-4050 3900);
PAINT SKYBLUE (-4050 3900);
FORCEPROP 1 LAST MATERIAL CHIP
J 0
(-4025 3850);
DISPLAY 0.489362 (-4025 3850);
PAINT SKYBLUE (-4025 3850);
FORCEPROP 1 LAST TOLERANCE 5%
J 0
(-4025 3975);
DISPLAY 0.489362 (-4025 3975);
PAINT SKYBLUE (-4025 3975);
FORCEPROP 1 LAST VALUE 0
J 2
(-4275 3975);
DISPLAY 0.489362 (-4275 3975);
PAINT SKYBLUE (-4275 3975);
FORCEPROP 1 LAST PART_NUMBER CS00002JB38
J 0
(-4400 3900);
DISPLAY 0.489362 (-4400 3900);
PAINT SKYBLUE (-4400 3900);
FORCEPROP 1 LAST PACK_TYPE 0402LF
J 0
(-4375 3850);
DISPLAY 0.489362 (-4375 3850);
PAINT SKYBLUE (-4375 3850);
FORCEPROP 2 LAST CDS_LIB pure_quanta
J 0
(-4150 3950);
DISPLAY INVISIBLE (-4150 3950);
FORCEPROP 1 LAST PATH I16
J 0
(-4200 4100);
DISPLAY 0.978723 (-4200 4100);
PAINT WHITE (-4200 4100);
DISPLAY INVISIBLE (-4200 4100);
FORCEADD Q_RES..1
(-4550 5250);
FORCEPROP 1 LAST LOCATION PR348
J 0
(-4600 5300);
DISPLAY 0.489362 (-4600 5300);
PAINT SKYBLUE (-4600 5300);
FORCEPROP 0 LAST $SEC 1
J 0
(-4525 5325);
DISPLAY 0.680851 (-4525 5325);
PAINT MONO (-4525 5325);
DISPLAY INVISIBLE (-4525 5325);
FORCEPROP 0 LAST CDS_SEC 1
J 0
(-4525 5325);
DISPLAY 1.021277 (-4525 5325);
DISPLAY INVISIBLE (-4525 5325);
FORCEPROP 1 LASTPIN (-4650 5250) $PN 1
J 0
(-4638 5262);
DISPLAY 0.489362 (-4638 5262);
PAINT MONO (-4638 5262);
FORCEPROP 1 LASTPIN (-4450 5250) $PN 2
J 0
(-4488 5262);
DISPLAY 0.489362 (-4488 5262);
PAINT MONO (-4488 5262);
FORCEPROP 1 LAST PACK_TYPE 0402LF
J 0
(-4450 5150);
DISPLAY 0.489362 (-4450 5150);
PAINT SKYBLUE (-4450 5150);
FORCEPROP 1 LAST TOLERANCE 1%
J 0
(-4425 5275);
DISPLAY 0.489362 (-4425 5275);
PAINT SKYBLUE (-4425 5275);
FORCEPROP 1 LAST MATERIAL CHIP
J 0
(-4800 5150);
DISPLAY 0.489362 (-4800 5150);
PAINT SKYBLUE (-4800 5150);
FORCEPROP 1 LAST WATTAGE 1/16W
J 0
(-4450 5200);
DISPLAY 0.489362 (-4450 5200);
PAINT SKYBLUE (-4450 5200);
FORCEPROP 1 LAST VALUE 4.7
J 2
(-4675 5275);
DISPLAY 0.489362 (-4675 5275);
PAINT SKYBLUE (-4675 5275);
FORCEPROP 1 LAST PART_NUMBER CS-4702FB19
J 0
(-4800 5200);
DISPLAY 0.489362 (-4800 5200);
PAINT SKYBLUE (-4800 5200);
FORCEPROP 1 LAST PATH I18
J 0
(-4600 5400);
DISPLAY 0.978723 (-4600 5400);
PAINT WHITE (-4600 5400);
DISPLAY INVISIBLE (-4600 5400);
FORCEPROP 2 LAST CDS_LIB pure_quanta
J 0
(-4550 5250);
DISPLAY INVISIBLE (-4550 5250);
FORCEADD Q_CAP..1
(-4975 5800);
FORCEPROP 1 LAST LOCATION PC552_3
J 0
(-4925 5900);
DISPLAY 0.489362 (-4925 5900);
PAINT SKYBLUE (-4925 5900);
FORCEPROP 0 LAST $SEC 1
J 0
(-4925 5925);
DISPLAY 0.680851 (-4925 5925);
PAINT MONO (-4925 5925);
DISPLAY INVISIBLE (-4925 5925);
FORCEPROP 0 LAST CDS_SEC 1
J 0
(-4925 5925);
DISPLAY 1.021277 (-4925 5925);
DISPLAY INVISIBLE (-4925 5925);
FORCEPROP 1 LASTPIN (-4975 5900) $PN 1
J 0
(-4965 5880);
DISPLAY 0.489362 (-4965 5880);
PAINT MONO (-4965 5880);
FORCEPROP 1 LASTPIN (-4975 5700) $PN 2
J 0
(-4965 5680);
DISPLAY 0.489362 (-4965 5680);
PAINT MONO (-4965 5680);
FORCEPROP 1 LAST MATERIAL X6S
J 0
(-4925 5700);
DISPLAY 0.489362 (-4925 5700);
PAINT SKYBLUE (-4925 5700);
FORCEPROP 1 LAST TOLERANCE 10%
J 0
(-4925 5750);
DISPLAY 0.489362 (-4925 5750);
PAINT SKYBLUE (-4925 5750);
FORCEPROP 1 LAST VALUE 1UF
J 0
(-4925 5850);
DISPLAY 0.489362 (-4925 5850);
PAINT SKYBLUE (-4925 5850);
FORCEPROP 1 LAST PART_NUMBER CH5104KEB02
J 0
(-4925 5650);
DISPLAY 0.489362 (-4925 5650);
PAINT SKYBLUE (-4925 5650);
FORCEPROP 1 LAST VOLTAGE 25V
J 0
(-4925 5800);
DISPLAY 0.489362 (-4925 5800);
PAINT SKYBLUE (-4925 5800);
FORCEPROP 1 LAST PACK_TYPE C0402
J 0
(-4925 5600);
DISPLAY 0.489362 (-4925 5600);
PAINT SKYBLUE (-4925 5600);
FORCEPROP 2 LAST CDS_LIB pure_quanta
J 0
(-4975 5800);
DISPLAY INVISIBLE (-4975 5800);
FORCEPROP 1 LAST PATH I19
J 0
(-4925 5950);
DISPLAY 0.978723 (-4925 5950);
PAINT WHITE (-4925 5950);
DISPLAY INVISIBLE (-4925 5950);
FORCEADD OFFPAGE..1
(-8000 4800);
FORCEPROP 2 LAST $XR5 175 
J 0
(-8852 4800);
DISPLAY 0.638298 (-8852 4800);
PAINT MONO (-8852 4800);
FORCEPROP 2 LAST $XR4 174 
J 0
(-8732 4800);
DISPLAY 0.638298 (-8732 4800);
PAINT MONO (-8732 4800);
FORCEPROP 2 LAST $XR3 172 
J 0
(-8612 4800);
DISPLAY 0.638298 (-8612 4800);
PAINT MONO (-8612 4800);
FORCEPROP 2 LAST $XR2 171 
J 0
(-8492 4800);
DISPLAY 0.638298 (-8492 4800);
PAINT MONO (-8492 4800);
FORCEPROP 2 LAST $XR1 170 
J 0
(-8372 4800);
DISPLAY 0.638298 (-8372 4800);
PAINT MONO (-8372 4800);
FORCEPROP 2 LAST $XR0 169 
J 0
(-8252 4800);
DISPLAY 0.638298 (-8252 4800);
PAINT MONO (-8252 4800);
FORCEPROP 2 LAST PATH I2
J 0
(-7950 4875);
DISPLAY 1.021277 (-7950 4875);
DISPLAY INVISIBLE (-7950 4875);
FORCEPROP 1 LAST COMMENT_BODY TRUE
J 0
(-7875 4700);
DISPLAY 0.872340 (-7875 4700);
PAINT GREEN (-7875 4700);
DISPLAY INVISIBLE (-7875 4700);
FORCEPROP 1 LAST OFFPAGE TRUE
J 0
(-7675 4675);
DISPLAY 0.872340 (-7675 4675);
PAINT GREEN (-7675 4675);
DISPLAY INVISIBLE (-7675 4675);
FORCEPROP 2 LAST CDS_LIB standard
J 0
(-8000 4800);
DISPLAY INVISIBLE (-8000 4800);
FORCEADD Q_CAP..1
(-4650 5800);
FORCEPROP 1 LAST LOCATION PC554_3
J 0
(-4600 5900);
DISPLAY 0.489362 (-4600 5900);
PAINT SKYBLUE (-4600 5900);
FORCEPROP 0 LAST $SEC 1
J 0
(-4600 5925);
DISPLAY 0.680851 (-4600 5925);
PAINT MONO (-4600 5925);
DISPLAY INVISIBLE (-4600 5925);
FORCEPROP 0 LAST CDS_SEC 1
J 0
(-4600 5925);
DISPLAY 1.021277 (-4600 5925);
DISPLAY INVISIBLE (-4600 5925);
FORCEPROP 1 LASTPIN (-4650 5900) $PN 1
J 0
(-4640 5880);
DISPLAY 0.489362 (-4640 5880);
PAINT MONO (-4640 5880);
FORCEPROP 1 LASTPIN (-4650 5700) $PN 2
J 0
(-4640 5680);
DISPLAY 0.489362 (-4640 5680);
PAINT MONO (-4640 5680);
FORCEPROP 1 LAST MATERIAL X6S
J 0
(-4600 5700);
DISPLAY 0.489362 (-4600 5700);
PAINT SKYBLUE (-4600 5700);
FORCEPROP 1 LAST TOLERANCE 10%
J 0
(-4600 5750);
DISPLAY 0.489362 (-4600 5750);
PAINT SKYBLUE (-4600 5750);
FORCEPROP 1 LAST VALUE 10UF
J 0
(-4600 5850);
DISPLAY 0.489362 (-4600 5850);
PAINT SKYBLUE (-4600 5850);
FORCEPROP 1 LAST VOLTAGE 25V
J 0
(-4600 5800);
DISPLAY 0.489362 (-4600 5800);
PAINT SKYBLUE (-4600 5800);
FORCEPROP 1 LAST PACK_TYPE C0805
J 0
(-4600 5600);
DISPLAY 0.489362 (-4600 5600);
PAINT SKYBLUE (-4600 5600);
FORCEPROP 1 LAST PART_NUMBER CH6104KEA00
J 0
(-4600 5650);
DISPLAY 0.489362 (-4600 5650);
PAINT SKYBLUE (-4600 5650);
FORCEPROP 2 LAST CDS_LIB pure_quanta
J 0
(-4650 5800);
DISPLAY INVISIBLE (-4650 5800);
FORCEPROP 1 LAST PATH I20
J 0
(-4600 5950);
DISPLAY 0.978723 (-4600 5950);
PAINT WHITE (-4600 5950);
DISPLAY INVISIBLE (-4600 5950);
FORCEADD Q_CAP..1
(-4325 5800);
FORCEPROP 1 LAST LOCATION PC556_3
J 0
(-4275 5900);
DISPLAY 0.489362 (-4275 5900);
PAINT SKYBLUE (-4275 5900);
FORCEPROP 0 LAST $SEC 1
J 0
(-4275 5925);
DISPLAY 0.680851 (-4275 5925);
PAINT MONO (-4275 5925);
DISPLAY INVISIBLE (-4275 5925);
FORCEPROP 0 LAST CDS_SEC 1
J 0
(-4275 5925);
DISPLAY 1.021277 (-4275 5925);
DISPLAY INVISIBLE (-4275 5925);
FORCEPROP 1 LASTPIN (-4325 5900) $PN 1
J 0
(-4315 5880);
DISPLAY 0.489362 (-4315 5880);
PAINT MONO (-4315 5880);
FORCEPROP 1 LASTPIN (-4325 5700) $PN 2
J 0
(-4315 5680);
DISPLAY 0.489362 (-4315 5680);
PAINT MONO (-4315 5680);
FORCEPROP 1 LAST VALUE 10UF
J 0
(-4275 5850);
DISPLAY 0.489362 (-4275 5850);
PAINT SKYBLUE (-4275 5850);
FORCEPROP 1 LAST PART_NUMBER CH6104KEA00
J 0
(-4275 5650);
DISPLAY 0.489362 (-4275 5650);
PAINT SKYBLUE (-4275 5650);
FORCEPROP 1 LAST VOLTAGE 25V
J 0
(-4275 5800);
DISPLAY 0.489362 (-4275 5800);
PAINT SKYBLUE (-4275 5800);
FORCEPROP 1 LAST PACK_TYPE C0805
J 0
(-4275 5600);
DISPLAY 0.489362 (-4275 5600);
PAINT SKYBLUE (-4275 5600);
FORCEPROP 1 LAST TOLERANCE 10%
J 0
(-4275 5750);
DISPLAY 0.489362 (-4275 5750);
PAINT SKYBLUE (-4275 5750);
FORCEPROP 1 LAST MATERIAL X6S
J 0
(-4275 5700);
DISPLAY 0.489362 (-4275 5700);
PAINT SKYBLUE (-4275 5700);
FORCEPROP 2 LAST CDS_LIB pure_quanta
J 0
(-4325 5800);
DISPLAY INVISIBLE (-4325 5800);
FORCEPROP 1 LAST PATH I21
J 0
(-4275 5950);
DISPLAY 0.978723 (-4275 5950);
PAINT WHITE (-4275 5950);
DISPLAY INVISIBLE (-4275 5950);
FORCEADD OFFPAGE..3
R 2
(-3775 4650);
FORCEPROP 2 LAST $XR0 170 
J 0
(-4085 4650);
DISPLAY 0.638298 (-4085 4650);
PAINT MONO (-4085 4650);
FORCEPROP 2 LAST PATH I22
J 0
(-3725 4725);
DISPLAY 1.021277 (-3725 4725);
DISPLAY INVISIBLE (-3725 4725);
FORCEPROP 1 LAST COMMENT_BODY TRUE
J 2
(-3725 4550);
DISPLAY 0.872340 (-3725 4550);
PAINT GREEN (-3725 4550);
DISPLAY INVISIBLE (-3725 4550);
FORCEPROP 1 LAST OFFPAGE TRUE
J 2
(-4100 4525);
DISPLAY 0.872340 (-4100 4525);
PAINT GREEN (-4100 4525);
DISPLAY INVISIBLE (-4100 4525);
FORCEPROP 2 LAST CDS_LIB standard
J 2
(-3775 4650);
DISPLAY INVISIBLE (-3775 4650);
FORCEADD Q_INDUCTOR4P_14..1
(-2825 4775);
FORCEPROP 1 LAST LOCATION PL59
J 0
(-3050 5030);
DISPLAY 0.489362 (-3050 5030);
PAINT SKYBLUE (-3050 5030);
FORCEPROP 0 LAST $SEC 1
J 0
(-3050 5175);
DISPLAY 0.680851 (-3050 5175);
PAINT MONO (-3050 5175);
DISPLAY INVISIBLE (-3050 5175);
FORCEPROP 0 LAST CDS_SEC 1
J 0
(-3050 5175);
DISPLAY 1.021277 (-3050 5175);
DISPLAY INVISIBLE (-3050 5175);
FORCEPROP 0 LASTPIN (-3225 4900) $PN 1
J 2
(-3235 4910);
DISPLAY 0.489362 (-3235 4910);
PAINT MONO (-3235 4910);
FORCEPROP 0 LASTPIN (-3225 4650) $PN 2
J 2
(-3235 4660);
DISPLAY 0.489362 (-3235 4660);
PAINT MONO (-3235 4660);
FORCEPROP 0 LASTPIN (-2425 4650) $PN 3
J 0
(-2415 4660);
DISPLAY 0.489362 (-2415 4660);
PAINT MONO (-2415 4660);
FORCEPROP 0 LASTPIN (-2425 4900) $PN 4
J 0
(-2415 4910);
DISPLAY 0.489362 (-2415 4910);
PAINT MONO (-2415 4910);
FORCEPROP 2 LAST PART_TYPE SMLF
J 0
(-3050 5125);
DISPLAY 1.021277 (-3050 5125);
FORCEPROP 1 LAST MATERIAL IND
J 0
(-3050 4985);
DISPLAY 0.489362 (-3050 4985);
PAINT SKYBLUE (-3050 4985);
FORCEPROP 2 LAST VALUE 150NH
J 0
(-3050 5075);
DISPLAY 0.489362 (-3050 5075);
PAINT SKYBLUE (-3050 5075);
FORCEPROP 1 LAST PART_NUMBER CV+15^0TZ04
J 0
(-3050 4935);
DISPLAY 0.489362 (-3050 4935);
PAINT SKYBLUE (-3050 4935);
FORCEPROP 2 LAST CDS_LIB pure_quanta
J 0
(-2825 4775);
DISPLAY INVISIBLE (-2825 4775);
FORCEPROP 1 LAST NEEDS_NO_SIZE TRUE
J 0
(-2825 4775);
DISPLAY 0.468085 (-2825 4775);
PAINT GREEN (-2825 4775);
DISPLAY INVISIBLE (-2825 4775);
FORCEPROP 1 LAST PATH I23
J 0
(-2625 4930);
DISPLAY 0.723404 (-2625 4930);
PAINT GREEN (-2625 4930);
DISPLAY INVISIBLE (-2625 4930);
FORCEADD Q_CAP..1
(-3550 5125);
FORCEPROP 1 LAST LOCATION PC560
J 0
(-3500 5250);
DISPLAY 0.489362 (-3500 5250);
PAINT SKYBLUE (-3500 5250);
FORCEPROP 0 LAST $SEC 1
J 0
(-3500 5275);
DISPLAY 0.680851 (-3500 5275);
PAINT MONO (-3500 5275);
DISPLAY INVISIBLE (-3500 5275);
FORCEPROP 0 LAST CDS_SEC 1
J 0
(-3500 5275);
DISPLAY 1.021277 (-3500 5275);
DISPLAY INVISIBLE (-3500 5275);
FORCEPROP 1 LASTPIN (-3550 5225) $PN 1
J 0
(-3540 5205);
DISPLAY 0.489362 (-3540 5205);
PAINT MONO (-3540 5205);
FORCEPROP 1 LASTPIN (-3550 5025) $PN 2
J 0
(-3540 5005);
DISPLAY 0.489362 (-3540 5005);
PAINT MONO (-3540 5005);
FORCEPROP 1 LAST MATERIAL X7R
J 0
(-3500 5050);
DISPLAY 0.489362 (-3500 5050);
PAINT SKYBLUE (-3500 5050);
FORCEPROP 1 LAST TOLERANCE 10%
J 0
(-3500 5100);
DISPLAY 0.489362 (-3500 5100);
PAINT SKYBLUE (-3500 5100);
FORCEPROP 1 LAST VALUE 0.22UF
J 0
(-3500 5200);
DISPLAY 0.489362 (-3500 5200);
PAINT SKYBLUE (-3500 5200);
FORCEPROP 1 LAST PART_NUMBER CH4223K1B00
J 0
(-3500 5000);
DISPLAY 0.489362 (-3500 5000);
PAINT SKYBLUE (-3500 5000);
FORCEPROP 1 LAST VOLTAGE 16V
J 0
(-3500 5150);
DISPLAY 0.489362 (-3500 5150);
PAINT SKYBLUE (-3500 5150);
FORCEPROP 1 LAST PACK_TYPE 0402
J 0
(-3500 4950);
DISPLAY 0.489362 (-3500 4950);
PAINT SKYBLUE (-3500 4950);
FORCEPROP 2 LAST CDS_LIB pure_quanta
J 0
(-3550 5125);
DISPLAY INVISIBLE (-3550 5125);
FORCEPROP 1 LAST PATH I26
J 0
(-3500 5275);
DISPLAY 0.978723 (-3500 5275);
PAINT WHITE (-3500 5275);
DISPLAY INVISIBLE (-3500 5275);
FORCEADD UNIVERSAL_GND..1
(-4025 5475);
FORCEPROP 3 LASTPIN (-4025 5525) SIG_NAME GND\g
J 0
(-4015 5535);
DISPLAY 0.659574 (-4015 5535);
PAINT MONO (-4015 5535);
DISPLAY INVISIBLE (-4015 5535);
FORCEPROP 2 LAST CDS_LIB pure_quanta_power
J 0
(-4025 5475);
DISPLAY INVISIBLE (-4025 5475);
FORCEPROP 1 LAST PATH I27
J 0
(-3950 5475);
DISPLAY 0.872340 (-3950 5475);
PAINT AQUA (-3950 5475);
DISPLAY INVISIBLE (-3950 5475);
FORCEPROP 1 LAST HDL_POWER GND
J 1
(-4000 5400);
DISPLAY 0.872340 (-4000 5400);
PAINT GREEN (-4000 5400);
DISPLAY INVISIBLE (-4000 5400);
FORCEADD Q_CAP..1
(-4025 5800);
FORCEPROP 1 LAST LOCATION PC558_3
J 0
(-3975 5900);
DISPLAY 0.489362 (-3975 5900);
PAINT SKYBLUE (-3975 5900);
FORCEPROP 0 LAST $SEC 1
J 0
(-3975 5925);
DISPLAY 0.680851 (-3975 5925);
PAINT MONO (-3975 5925);
DISPLAY INVISIBLE (-3975 5925);
FORCEPROP 0 LAST CDS_SEC 1
J 0
(-3975 5925);
DISPLAY 1.021277 (-3975 5925);
DISPLAY INVISIBLE (-3975 5925);
FORCEPROP 1 LASTPIN (-4025 5900) $PN 1
J 0
(-4015 5880);
DISPLAY 0.489362 (-4015 5880);
PAINT MONO (-4015 5880);
FORCEPROP 1 LASTPIN (-4025 5700) $PN 2
J 0
(-4015 5680);
DISPLAY 0.489362 (-4015 5680);
PAINT MONO (-4015 5680);
FORCEPROP 1 LAST MATERIAL X6S
J 0
(-3975 5700);
DISPLAY 0.489362 (-3975 5700);
PAINT SKYBLUE (-3975 5700);
FORCEPROP 1 LAST TOLERANCE 10%
J 0
(-3975 5750);
DISPLAY 0.489362 (-3975 5750);
PAINT SKYBLUE (-3975 5750);
FORCEPROP 1 LAST VALUE 10UF
J 0
(-3975 5850);
DISPLAY 0.489362 (-3975 5850);
PAINT SKYBLUE (-3975 5850);
FORCEPROP 1 LAST PART_NUMBER CH6104KEA00
J 0
(-3975 5650);
DISPLAY 0.489362 (-3975 5650);
PAINT SKYBLUE (-3975 5650);
FORCEPROP 1 LAST VOLTAGE 25V
J 0
(-3975 5800);
DISPLAY 0.489362 (-3975 5800);
PAINT SKYBLUE (-3975 5800);
FORCEPROP 1 LAST PACK_TYPE C0805
J 0
(-3975 5600);
DISPLAY 0.489362 (-3975 5600);
PAINT SKYBLUE (-3975 5600);
FORCEPROP 2 LAST CDS_LIB pure_quanta
J 0
(-4025 5800);
DISPLAY INVISIBLE (-4025 5800);
FORCEPROP 1 LAST PATH I28
J 0
(-3975 5950);
DISPLAY 0.978723 (-3975 5950);
PAINT WHITE (-3975 5950);
DISPLAY INVISIBLE (-3975 5950);
FORCEADD VCC_CORE..1
(-4025 6100);
FORCEPROP 3 LASTPIN (-4025 6050) SIG_NAME SW_P12V_STBY_PVDDCR_CPU0_P0_FLT\g
J 0
(-4015 6060);
DISPLAY 0.659574 (-4015 6060);
PAINT MONO (-4015 6060);
DISPLAY INVISIBLE (-4015 6060);
FORCEPROP 1 LAST HDL_POWER SW_P12V_STBY_PVDDCR_CPU0_P0_FLT
J 1
(-4025 6150);
DISPLAY 0.489362 (-4025 6150);
PAINT GREEN (-4025 6150);
FORCEPROP 2 LAST CDS_LIB pure_quanta_power
J 0
(-4025 6100);
DISPLAY INVISIBLE (-4025 6100);
FORCEPROP 1 LAST PATH I29
J 0
(-3975 6125);
DISPLAY 0.872340 (-3975 6125);
PAINT AQUA (-3975 6125);
DISPLAY INVISIBLE (-3975 6125);
FORCEADD Q_CAP..1
(-7775 4625);
FORCEPROP 1 LAST LOCATION PC544_3
J 0
(-7725 4725);
DISPLAY 0.489362 (-7725 4725);
PAINT SKYBLUE (-7725 4725);
FORCEPROP 0 LAST $SEC 1
J 0
(-7725 4750);
DISPLAY 0.680851 (-7725 4750);
PAINT MONO (-7725 4750);
DISPLAY INVISIBLE (-7725 4750);
FORCEPROP 0 LAST CDS_SEC 1
J 0
(-7725 4750);
DISPLAY 1.021277 (-7725 4750);
DISPLAY INVISIBLE (-7725 4750);
FORCEPROP 1 LASTPIN (-7775 4725) $PN 1
J 0
(-7765 4705);
DISPLAY 0.489362 (-7765 4705);
PAINT MONO (-7765 4705);
FORCEPROP 1 LASTPIN (-7775 4525) $PN 2
J 0
(-7765 4505);
DISPLAY 0.489362 (-7765 4505);
PAINT MONO (-7765 4505);
FORCEPROP 1 LAST MATERIAL X7R
J 0
(-7725 4525);
DISPLAY 0.489362 (-7725 4525);
PAINT SKYBLUE (-7725 4525);
FORCEPROP 1 LAST TOLERANCE 10%
J 0
(-7725 4575);
DISPLAY 0.489362 (-7725 4575);
PAINT SKYBLUE (-7725 4575);
FORCEPROP 1 LAST VALUE 0.1UF
J 0
(-7725 4675);
DISPLAY 0.489362 (-7725 4675);
PAINT SKYBLUE (-7725 4675);
FORCEPROP 1 LAST PART_NUMBER CH4104K1B00
J 0
(-7725 4475);
DISPLAY 0.489362 (-7725 4475);
PAINT SKYBLUE (-7725 4475);
FORCEPROP 1 LAST VOLTAGE 25V
J 0
(-7725 4625);
DISPLAY 0.489362 (-7725 4625);
PAINT SKYBLUE (-7725 4625);
FORCEPROP 1 LAST PACK_TYPE 0402
J 0
(-7725 4425);
DISPLAY 0.489362 (-7725 4425);
PAINT SKYBLUE (-7725 4425);
FORCEPROP 2 LAST CDS_LIB pure_quanta
J 0
(-7775 4625);
DISPLAY INVISIBLE (-7775 4625);
FORCEPROP 1 LAST PATH I3
J 0
(-7725 4775);
DISPLAY 0.978723 (-7725 4775);
PAINT WHITE (-7725 4775);
DISPLAY INVISIBLE (-7725 4775);
FORCEADD Q_CAP..1
(-1500 4725);
FORCEPROP 1 LAST LOCATION PC562_3
J 0
(-1450 4825);
DISPLAY 0.489362 (-1450 4825);
PAINT SKYBLUE (-1450 4825);
FORCEPROP 0 LAST $SEC 1
J 0
(-1450 4850);
DISPLAY 0.680851 (-1450 4850);
PAINT MONO (-1450 4850);
DISPLAY INVISIBLE (-1450 4850);
FORCEPROP 0 LAST CDS_SEC 1
J 0
(-1450 4850);
DISPLAY 1.021277 (-1450 4850);
DISPLAY INVISIBLE (-1450 4850);
FORCEPROP 1 LASTPIN (-1500 4825) $PN 1
J 0
(-1490 4805);
DISPLAY 0.489362 (-1490 4805);
PAINT MONO (-1490 4805);
FORCEPROP 1 LASTPIN (-1500 4625) $PN 2
J 0
(-1490 4605);
DISPLAY 0.489362 (-1490 4605);
PAINT MONO (-1490 4605);
FORCEPROP 1 LAST MATERIAL X6S
J 0
(-1450 4625);
DISPLAY 0.489362 (-1450 4625);
PAINT SKYBLUE (-1450 4625);
FORCEPROP 1 LAST TOLERANCE 20%
J 0
(-1450 4675);
DISPLAY 0.489362 (-1450 4675);
PAINT SKYBLUE (-1450 4675);
FORCEPROP 1 LAST VALUE 22UF
J 0
(-1450 4775);
DISPLAY 0.489362 (-1450 4775);
PAINT SKYBLUE (-1450 4775);
FORCEPROP 1 LAST PART_NUMBER TMP_QCH622KMEA01
J 0
(-1450 4575);
DISPLAY 0.489362 (-1450 4575);
PAINT SKYBLUE (-1450 4575);
FORCEPROP 1 LAST VOLTAGE 4V
J 0
(-1450 4725);
DISPLAY 0.489362 (-1450 4725);
PAINT SKYBLUE (-1450 4725);
FORCEPROP 1 LAST PACK_TYPE 0805
J 0
(-1450 4525);
DISPLAY 0.489362 (-1450 4525);
PAINT SKYBLUE (-1450 4525);
FORCEPROP 2 LAST CDS_LIB pure_quanta
J 0
(-1500 4725);
DISPLAY INVISIBLE (-1500 4725);
FORCEPROP 1 LAST PATH I31
J 0
(-1450 4875);
DISPLAY 0.978723 (-1450 4875);
PAINT WHITE (-1450 4875);
DISPLAY INVISIBLE (-1450 4875);
FORCEADD UNIVERSAL_GND..1
(-1075 4375);
FORCEPROP 3 LASTPIN (-1075 4425) SIG_NAME GND\g
J 0
(-1065 4435);
DISPLAY 0.659574 (-1065 4435);
PAINT MONO (-1065 4435);
DISPLAY INVISIBLE (-1065 4435);
FORCEPROP 2 LAST CDS_LIB pure_quanta_power
J 0
(-1075 4375);
DISPLAY INVISIBLE (-1075 4375);
FORCEPROP 1 LAST PATH I32
J 0
(-1000 4375);
DISPLAY 0.872340 (-1000 4375);
PAINT AQUA (-1000 4375);
DISPLAY INVISIBLE (-1000 4375);
FORCEPROP 1 LAST HDL_POWER GND
J 1
(-1050 4300);
DISPLAY 0.872340 (-1050 4300);
PAINT GREEN (-1050 4300);
DISPLAY INVISIBLE (-1050 4300);
FORCEADD Q_CAP..1
(-1075 4725);
FORCEPROP 1 LAST LOCATION PC564_3
J 0
(-1025 4825);
DISPLAY 0.489362 (-1025 4825);
PAINT SKYBLUE (-1025 4825);
FORCEPROP 0 LAST $SEC 1
J 0
(-1025 4850);
DISPLAY 0.680851 (-1025 4850);
PAINT MONO (-1025 4850);
DISPLAY INVISIBLE (-1025 4850);
FORCEPROP 0 LAST CDS_SEC 1
J 0
(-1025 4850);
DISPLAY 1.021277 (-1025 4850);
DISPLAY INVISIBLE (-1025 4850);
FORCEPROP 1 LASTPIN (-1075 4825) $PN 1
J 0
(-1065 4805);
DISPLAY 0.489362 (-1065 4805);
PAINT MONO (-1065 4805);
FORCEPROP 1 LASTPIN (-1075 4625) $PN 2
J 0
(-1065 4605);
DISPLAY 0.489362 (-1065 4605);
PAINT MONO (-1065 4605);
FORCEPROP 1 LAST MATERIAL X6S
J 0
(-1025 4625);
DISPLAY 0.489362 (-1025 4625);
PAINT SKYBLUE (-1025 4625);
FORCEPROP 1 LAST TOLERANCE 20%
J 0
(-1025 4675);
DISPLAY 0.489362 (-1025 4675);
PAINT SKYBLUE (-1025 4675);
FORCEPROP 1 LAST VALUE 22UF
J 0
(-1025 4775);
DISPLAY 0.489362 (-1025 4775);
PAINT SKYBLUE (-1025 4775);
FORCEPROP 1 LAST PART_NUMBER TMP_QCH622KMEA01
J 0
(-1025 4575);
DISPLAY 0.489362 (-1025 4575);
PAINT SKYBLUE (-1025 4575);
FORCEPROP 1 LAST VOLTAGE 4V
J 0
(-1025 4725);
DISPLAY 0.489362 (-1025 4725);
PAINT SKYBLUE (-1025 4725);
FORCEPROP 1 LAST PACK_TYPE 0805
J 0
(-1025 4525);
DISPLAY 0.489362 (-1025 4525);
PAINT SKYBLUE (-1025 4525);
FORCEPROP 2 LAST CDS_LIB pure_quanta
J 0
(-1075 4725);
DISPLAY INVISIBLE (-1075 4725);
FORCEPROP 1 LAST PATH I33
J 0
(-1025 4875);
DISPLAY 0.978723 (-1025 4875);
PAINT WHITE (-1025 4875);
DISPLAY INVISIBLE (-1025 4875);
FORCEADD VCC_CORE..1
(-1075 5050);
FORCEPROP 3 LASTPIN (-1075 5000) SIG_NAME PVDDCR_CPU0_P0\g
J 0
(-1065 5010);
DISPLAY 0.659574 (-1065 5010);
PAINT MONO (-1065 5010);
DISPLAY INVISIBLE (-1065 5010);
FORCEPROP 1 LAST HDL_POWER PVDDCR_CPU0_P0
J 1
(-1075 5100);
DISPLAY 0.489362 (-1075 5100);
PAINT GREEN (-1075 5100);
FORCEPROP 2 LAST CDS_LIB pure_quanta_power
J 0
(-1075 5050);
DISPLAY INVISIBLE (-1075 5050);
FORCEPROP 1 LAST PATH I34
J 0
(-1025 5075);
DISPLAY 0.872340 (-1025 5075);
PAINT AQUA (-1025 5075);
DISPLAY INVISIBLE (-1025 5075);
FORCEADD UNIVERSAL_GND..1
(-7450 4425);
FORCEPROP 3 LASTPIN (-7450 4475) SIG_NAME GND\g
J 0
(-7440 4485);
DISPLAY 0.659574 (-7440 4485);
PAINT MONO (-7440 4485);
DISPLAY INVISIBLE (-7440 4485);
FORCEPROP 2 LAST CDS_LIB pure_quanta_power
J 0
(-7450 4425);
DISPLAY INVISIBLE (-7450 4425);
FORCEPROP 1 LAST PATH I4
J 0
(-7375 4425);
DISPLAY 0.872340 (-7375 4425);
PAINT AQUA (-7375 4425);
DISPLAY INVISIBLE (-7375 4425);
FORCEPROP 1 LAST HDL_POWER GND
J 1
(-7425 4350);
DISPLAY 0.872340 (-7425 4350);
PAINT GREEN (-7425 4350);
DISPLAY INVISIBLE (-7425 4350);
FORCEADD OFFPAGE..2
R 2
(-7100 4900);
FORCEPROP 2 LAST $XR0 169 
J 0
(-7355 4900);
DISPLAY 0.638298 (-7355 4900);
PAINT MONO (-7355 4900);
FORCEPROP 2 LAST PATH I5
J 0
(-7050 4975);
DISPLAY 1.021277 (-7050 4975);
DISPLAY INVISIBLE (-7050 4975);
FORCEPROP 1 LAST COMMENT_BODY TRUE
J 2
(-7055 4805);
DISPLAY 0.872340 (-7055 4805);
PAINT GREEN (-7055 4805);
DISPLAY INVISIBLE (-7055 4805);
FORCEPROP 1 LAST OFFPAGE TRUE
J 2
(-7425 4775);
DISPLAY 0.872340 (-7425 4775);
PAINT GREEN (-7425 4775);
DISPLAY INVISIBLE (-7425 4775);
FORCEPROP 2 LAST CDS_LIB standard
J 2
(-7100 4900);
DISPLAY INVISIBLE (-7100 4900);
FORCEADD OFFPAGE..2
R 2
(-7075 4400);
FORCEPROP 2 LAST $XR3 169 
J 0
(-7600 4364);
DISPLAY 0.638298 (-7600 4364);
PAINT MONO (-7600 4364);
FORCEPROP 2 LAST $XR2 172 
J 0
(-7480 4364);
DISPLAY 0.638298 (-7480 4364);
PAINT MONO (-7480 4364);
FORCEPROP 2 LAST $XR1 171 
J 0
(-7360 4364);
DISPLAY 0.638298 (-7360 4364);
PAINT MONO (-7360 4364);
FORCEPROP 2 LAST $XR0 170 
J 0
(-7360 4400);
DISPLAY 0.638298 (-7360 4400);
PAINT MONO (-7360 4400);
FORCEPROP 2 LAST PATH I6
J 0
(-7025 4475);
DISPLAY 1.021277 (-7025 4475);
DISPLAY INVISIBLE (-7025 4475);
FORCEPROP 1 LAST COMMENT_BODY TRUE
J 2
(-7030 4305);
DISPLAY 0.872340 (-7030 4305);
PAINT GREEN (-7030 4305);
DISPLAY INVISIBLE (-7030 4305);
FORCEPROP 1 LAST OFFPAGE TRUE
J 2
(-7400 4275);
DISPLAY 0.872340 (-7400 4275);
PAINT GREEN (-7400 4275);
DISPLAY INVISIBLE (-7400 4275);
FORCEPROP 2 LAST CDS_LIB standard
J 0
(-7075 4400);
DISPLAY INVISIBLE (-7075 4400);
FORCEADD OFFPAGE..1
(-7050 4300);
FORCEPROP 2 LAST $XR0 169 
J 0
(-7302 4300);
DISPLAY 0.638298 (-7302 4300);
PAINT MONO (-7302 4300);
FORCEPROP 2 LAST PATH I7
J 0
(-7000 4375);
DISPLAY 1.021277 (-7000 4375);
DISPLAY INVISIBLE (-7000 4375);
FORCEPROP 1 LAST COMMENT_BODY TRUE
J 0
(-6925 4200);
DISPLAY 0.872340 (-6925 4200);
PAINT GREEN (-6925 4200);
DISPLAY INVISIBLE (-6925 4200);
FORCEPROP 1 LAST OFFPAGE TRUE
J 0
(-6725 4175);
DISPLAY 0.872340 (-6725 4175);
PAINT GREEN (-6725 4175);
DISPLAY INVISIBLE (-6725 4175);
FORCEPROP 2 LAST CDS_LIB standard
J 2
(-7050 4300);
DISPLAY INVISIBLE (-7050 4300);
FORCEADD OFFPAGE..3
(-1950 4650);
FORCEPROP 2 LAST $XR0 171 
J 0
(-1676 4650);
DISPLAY 0.638298 (-1676 4650);
PAINT MONO (-1676 4650);
FORCEPROP 2 LAST CDS_LIB standard
J 2
(-1950 4650);
DISPLAY INVISIBLE (-1950 4650);
FORCEPROP 1 LAST OFFPAGE TRUE
J 0
(-1625 4525);
DISPLAY 0.872340 (-1625 4525);
PAINT GREEN (-1625 4525);
DISPLAY INVISIBLE (-1625 4525);
FORCEPROP 1 LAST COMMENT_BODY TRUE
J 0
(-2000 4550);
DISPLAY 0.872340 (-2000 4550);
PAINT GREEN (-2000 4550);
DISPLAY INVISIBLE (-2000 4550);
FORCEPROP 2 LAST PATH I71
J 2
(-2000 4725);
DISPLAY 1.021277 (-2000 4725);
DISPLAY INVISIBLE (-2000 4725);
FORCEADD OFFPAGE..3
R 2
(-3675 1350);
FORCEPROP 2 LAST $XR0 171 
J 0
(-3985 1350);
DISPLAY 0.638298 (-3985 1350);
PAINT MONO (-3985 1350);
FORCEPROP 2 LAST PATH I73
J 0
(-3625 1425);
DISPLAY 1.021277 (-3625 1425);
DISPLAY INVISIBLE (-3625 1425);
FORCEPROP 1 LAST COMMENT_BODY TRUE
J 2
(-3625 1250);
DISPLAY 0.872340 (-3625 1250);
PAINT GREEN (-3625 1250);
DISPLAY INVISIBLE (-3625 1250);
FORCEPROP 1 LAST OFFPAGE TRUE
J 2
(-4000 1225);
DISPLAY 0.872340 (-4000 1225);
PAINT GREEN (-4000 1225);
DISPLAY INVISIBLE (-4000 1225);
FORCEPROP 2 LAST CDS_LIB standard
J 2
(-3675 1350);
DISPLAY INVISIBLE (-3675 1350);
FORCEADD VCC_CORE..1
(-900 1750);
FORCEPROP 3 LASTPIN (-900 1700) SIG_NAME PVDDCR_CPU0_P0\g
J 0
(-890 1710);
DISPLAY 0.659574 (-890 1710);
PAINT MONO (-890 1710);
DISPLAY INVISIBLE (-890 1710);
FORCEPROP 1 LAST HDL_POWER PVDDCR_CPU0_P0
J 1
(-900 1800);
DISPLAY 0.489362 (-900 1800);
PAINT GREEN (-900 1800);
FORCEPROP 2 LAST CDS_LIB pure_quanta_power
J 0
(-900 1750);
DISPLAY INVISIBLE (-900 1750);
FORCEPROP 1 LAST PATH I74
J 0
(-850 1775);
DISPLAY 0.872340 (-850 1775);
PAINT AQUA (-850 1775);
DISPLAY INVISIBLE (-850 1775);
FORCEADD Q_CAP..1
(-900 1425);
FORCEPROP 1 LAST LOCATION PC565_4
J 0
(-850 1525);
DISPLAY 0.489362 (-850 1525);
PAINT SKYBLUE (-850 1525);
FORCEPROP 0 LAST $SEC 1
J 0
(-850 1550);
DISPLAY 0.680851 (-850 1550);
PAINT MONO (-850 1550);
DISPLAY INVISIBLE (-850 1550);
FORCEPROP 0 LAST CDS_SEC 1
J 0
(-850 1550);
DISPLAY 1.021277 (-850 1550);
DISPLAY INVISIBLE (-850 1550);
FORCEPROP 1 LASTPIN (-900 1525) $PN 1
J 0
(-890 1505);
DISPLAY 0.489362 (-890 1505);
PAINT MONO (-890 1505);
FORCEPROP 1 LASTPIN (-900 1325) $PN 2
J 0
(-890 1305);
DISPLAY 0.489362 (-890 1305);
PAINT MONO (-890 1305);
FORCEPROP 1 LAST MATERIAL X6S
J 0
(-850 1325);
DISPLAY 0.489362 (-850 1325);
PAINT SKYBLUE (-850 1325);
FORCEPROP 1 LAST TOLERANCE 20%
J 0
(-850 1375);
DISPLAY 0.489362 (-850 1375);
PAINT SKYBLUE (-850 1375);
FORCEPROP 1 LAST VALUE 22UF
J 0
(-850 1475);
DISPLAY 0.489362 (-850 1475);
PAINT SKYBLUE (-850 1475);
FORCEPROP 1 LAST PART_NUMBER TMP_QCH622KMEA01
J 0
(-850 1275);
DISPLAY 0.489362 (-850 1275);
PAINT SKYBLUE (-850 1275);
FORCEPROP 1 LAST VOLTAGE 4V
J 0
(-850 1425);
DISPLAY 0.489362 (-850 1425);
PAINT SKYBLUE (-850 1425);
FORCEPROP 1 LAST PACK_TYPE 0805
J 0
(-850 1225);
DISPLAY 0.489362 (-850 1225);
PAINT SKYBLUE (-850 1225);
FORCEPROP 2 LAST CDS_LIB pure_quanta
J 0
(-900 1425);
DISPLAY INVISIBLE (-900 1425);
FORCEPROP 1 LAST PATH I75
J 0
(-850 1575);
DISPLAY 0.978723 (-850 1575);
PAINT WHITE (-850 1575);
DISPLAY INVISIBLE (-850 1575);
FORCEADD UNIVERSAL_GND..1
(-900 925);
FORCEPROP 3 LASTPIN (-900 975) SIG_NAME GND\g
J 0
(-890 985);
DISPLAY 0.659574 (-890 985);
PAINT MONO (-890 985);
DISPLAY INVISIBLE (-890 985);
FORCEPROP 2 LAST CDS_LIB pure_quanta_power
J 0
(-900 925);
DISPLAY INVISIBLE (-900 925);
FORCEPROP 1 LAST PATH I76
J 0
(-825 925);
DISPLAY 0.872340 (-825 925);
PAINT AQUA (-825 925);
DISPLAY INVISIBLE (-825 925);
FORCEPROP 1 LAST HDL_POWER GND
J 1
(-875 850);
DISPLAY 0.872340 (-875 850);
PAINT GREEN (-875 850);
DISPLAY INVISIBLE (-875 850);
FORCEADD Q_CAP..1
(-1400 1425);
FORCEPROP 1 LAST LOCATION PC563_4
J 0
(-1350 1525);
DISPLAY 0.489362 (-1350 1525);
PAINT SKYBLUE (-1350 1525);
FORCEPROP 0 LAST $SEC 1
J 0
(-1350 1550);
DISPLAY 0.680851 (-1350 1550);
PAINT MONO (-1350 1550);
DISPLAY INVISIBLE (-1350 1550);
FORCEPROP 0 LAST CDS_SEC 1
J 0
(-1350 1550);
DISPLAY 1.021277 (-1350 1550);
DISPLAY INVISIBLE (-1350 1550);
FORCEPROP 1 LASTPIN (-1400 1525) $PN 1
J 0
(-1390 1505);
DISPLAY 0.489362 (-1390 1505);
PAINT MONO (-1390 1505);
FORCEPROP 1 LASTPIN (-1400 1325) $PN 2
J 0
(-1390 1305);
DISPLAY 0.489362 (-1390 1305);
PAINT MONO (-1390 1305);
FORCEPROP 1 LAST MATERIAL X6S
J 0
(-1350 1325);
DISPLAY 0.489362 (-1350 1325);
PAINT SKYBLUE (-1350 1325);
FORCEPROP 1 LAST TOLERANCE 20%
J 0
(-1350 1375);
DISPLAY 0.489362 (-1350 1375);
PAINT SKYBLUE (-1350 1375);
FORCEPROP 1 LAST VALUE 22UF
J 0
(-1350 1475);
DISPLAY 0.489362 (-1350 1475);
PAINT SKYBLUE (-1350 1475);
FORCEPROP 1 LAST PART_NUMBER TMP_QCH622KMEA01
J 0
(-1350 1275);
DISPLAY 0.489362 (-1350 1275);
PAINT SKYBLUE (-1350 1275);
FORCEPROP 1 LAST VOLTAGE 4V
J 0
(-1350 1425);
DISPLAY 0.489362 (-1350 1425);
PAINT SKYBLUE (-1350 1425);
FORCEPROP 1 LAST PACK_TYPE 0805
J 0
(-1350 1225);
DISPLAY 0.489362 (-1350 1225);
PAINT SKYBLUE (-1350 1225);
FORCEPROP 2 LAST CDS_LIB pure_quanta
J 0
(-1400 1425);
DISPLAY INVISIBLE (-1400 1425);
FORCEPROP 1 LAST PATH I77
J 0
(-1350 1575);
DISPLAY 0.978723 (-1350 1575);
PAINT WHITE (-1350 1575);
DISPLAY INVISIBLE (-1350 1575);
FORCEADD Q_RES..1
(-7125 4600);
FORCEPROP 1 LAST LOCATION PR346
J 0
(-7175 4650);
DISPLAY 0.489362 (-7175 4650);
PAINT SKYBLUE (-7175 4650);
FORCEPROP 0 LAST $SEC 1
J 0
(-7125 4675);
DISPLAY 0.680851 (-7125 4675);
PAINT MONO (-7125 4675);
DISPLAY INVISIBLE (-7125 4675);
FORCEPROP 0 LAST CDS_SEC 1
J 0
(-7125 4675);
DISPLAY 1.021277 (-7125 4675);
DISPLAY INVISIBLE (-7125 4675);
FORCEPROP 1 LASTPIN (-7225 4600) $PN 1
J 0
(-7213 4612);
DISPLAY 0.489362 (-7213 4612);
PAINT MONO (-7213 4612);
FORCEPROP 1 LASTPIN (-7025 4600) $PN 2
J 0
(-7063 4612);
DISPLAY 0.489362 (-7063 4612);
PAINT MONO (-7063 4612);
FORCEPROP 1 LAST WATTAGE 1/16W
J 0
(-7025 4500);
DISPLAY 0.489362 (-7025 4500);
PAINT SKYBLUE (-7025 4500);
FORCEPROP 1 LAST MATERIAL EMPTY
J 0
(-7425 4500);
DISPLAY 0.489362 (-7425 4500);
PAINT RED (-7425 4500);
FORCEPROP 1 LAST TOLERANCE 1%
J 0
(-7000 4625);
DISPLAY 0.489362 (-7000 4625);
PAINT SKYBLUE (-7000 4625);
FORCEPROP 1 LAST VALUE 8.87K
J 2
(-7250 4625);
DISPLAY 0.489362 (-7250 4625);
PAINT SKYBLUE (-7250 4625);
FORCEPROP 1 LAST PART_NUMBER CS28872FB01
J 0
(-7425 4550);
DISPLAY 0.489362 (-7425 4550);
PAINT SKYBLUE (-7425 4550);
FORCEPROP 1 LAST PACK_TYPE 0402LF
J 0
(-7025 4550);
DISPLAY 0.489362 (-7025 4550);
PAINT SKYBLUE (-7025 4550);
FORCEPROP 2 LAST CDS_LIB pure_quanta
J 0
(-7125 4600);
DISPLAY INVISIBLE (-7125 4600);
FORCEPROP 1 LAST PATH I8
J 0
(-7175 4750);
DISPLAY 0.978723 (-7175 4750);
PAINT WHITE (-7175 4750);
DISPLAY INVISIBLE (-7175 4750);
FORCEADD VCC_CORE..1
(-3800 2800);
FORCEPROP 3 LASTPIN (-3800 2750) SIG_NAME SW_P12V_STBY_PVDDCR_CPU0_P0_FLT\g
J 0
(-3790 2760);
DISPLAY 0.659574 (-3790 2760);
PAINT MONO (-3790 2760);
DISPLAY INVISIBLE (-3790 2760);
FORCEPROP 1 LAST HDL_POWER SW_P12V_STBY_PVDDCR_CPU0_P0_FLT
J 1
(-3800 2850);
DISPLAY 0.489362 (-3800 2850);
PAINT GREEN (-3800 2850);
FORCEPROP 2 LAST CDS_LIB pure_quanta_power
J 0
(-3800 2800);
DISPLAY INVISIBLE (-3800 2800);
FORCEPROP 1 LAST PATH I81
J 0
(-3750 2825);
DISPLAY 0.872340 (-3750 2825);
PAINT AQUA (-3750 2825);
DISPLAY INVISIBLE (-3750 2825);
FORCEADD Q_CAP..1
(-3800 2500);
FORCEPROP 1 LAST LOCATION PC559_4
J 0
(-3750 2600);
DISPLAY 0.489362 (-3750 2600);
PAINT SKYBLUE (-3750 2600);
FORCEPROP 0 LAST $SEC 1
J 0
(-3750 2625);
DISPLAY 0.680851 (-3750 2625);
PAINT MONO (-3750 2625);
DISPLAY INVISIBLE (-3750 2625);
FORCEPROP 0 LAST CDS_SEC 1
J 0
(-3750 2625);
DISPLAY 1.021277 (-3750 2625);
DISPLAY INVISIBLE (-3750 2625);
FORCEPROP 1 LASTPIN (-3800 2600) $PN 1
J 0
(-3790 2580);
DISPLAY 0.489362 (-3790 2580);
PAINT MONO (-3790 2580);
FORCEPROP 1 LASTPIN (-3800 2400) $PN 2
J 0
(-3790 2380);
DISPLAY 0.489362 (-3790 2380);
PAINT MONO (-3790 2380);
FORCEPROP 1 LAST VALUE 10UF
J 0
(-3750 2550);
DISPLAY 0.489362 (-3750 2550);
PAINT SKYBLUE (-3750 2550);
FORCEPROP 1 LAST VOLTAGE 25V
J 0
(-3750 2500);
DISPLAY 0.489362 (-3750 2500);
PAINT SKYBLUE (-3750 2500);
FORCEPROP 1 LAST TOLERANCE 10%
J 0
(-3750 2450);
DISPLAY 0.489362 (-3750 2450);
PAINT SKYBLUE (-3750 2450);
FORCEPROP 1 LAST MATERIAL X6S
J 0
(-3750 2400);
DISPLAY 0.489362 (-3750 2400);
PAINT SKYBLUE (-3750 2400);
FORCEPROP 1 LAST PART_NUMBER CH6104KEA00
J 0
(-3750 2350);
DISPLAY 0.489362 (-3750 2350);
PAINT SKYBLUE (-3750 2350);
FORCEPROP 1 LAST PACK_TYPE C0805
J 0
(-3750 2300);
DISPLAY 0.489362 (-3750 2300);
PAINT SKYBLUE (-3750 2300);
FORCEPROP 2 LAST CDS_LIB pure_quanta
J 0
(-3800 2500);
DISPLAY INVISIBLE (-3800 2500);
FORCEPROP 1 LAST PATH I82
J 0
(-3750 2650);
DISPLAY 0.978723 (-3750 2650);
PAINT WHITE (-3750 2650);
DISPLAY INVISIBLE (-3750 2650);
FORCEADD UNIVERSAL_GND..1
(-3800 2150);
FORCEPROP 3 LASTPIN (-3800 2200) SIG_NAME GND\g
J 0
(-3790 2210);
DISPLAY 0.659574 (-3790 2210);
PAINT MONO (-3790 2210);
DISPLAY INVISIBLE (-3790 2210);
FORCEPROP 2 LAST CDS_LIB pure_quanta_power
J 0
(-3800 2150);
DISPLAY INVISIBLE (-3800 2150);
FORCEPROP 1 LAST PATH I83
J 0
(-3725 2150);
DISPLAY 0.872340 (-3725 2150);
PAINT AQUA (-3725 2150);
DISPLAY INVISIBLE (-3725 2150);
FORCEPROP 1 LAST HDL_POWER GND
J 1
(-3775 2075);
DISPLAY 0.872340 (-3775 2075);
PAINT GREEN (-3775 2075);
DISPLAY INVISIBLE (-3775 2075);
FORCEADD Q_INDUCTOR4P_14..1
(-2800 1475);
FORCEPROP 1 LAST LOCATION PL60
J 0
(-3025 1730);
DISPLAY 0.489362 (-3025 1730);
PAINT SKYBLUE (-3025 1730);
FORCEPROP 0 LAST $SEC 1
J 0
(-3025 1875);
DISPLAY 0.680851 (-3025 1875);
PAINT MONO (-3025 1875);
DISPLAY INVISIBLE (-3025 1875);
FORCEPROP 0 LAST CDS_SEC 1
J 0
(-3025 1875);
DISPLAY 1.021277 (-3025 1875);
DISPLAY INVISIBLE (-3025 1875);
FORCEPROP 0 LASTPIN (-3200 1600) $PN 1
J 2
(-3210 1610);
DISPLAY 0.489362 (-3210 1610);
PAINT MONO (-3210 1610);
FORCEPROP 0 LASTPIN (-3200 1350) $PN 2
J 2
(-3210 1360);
DISPLAY 0.489362 (-3210 1360);
PAINT MONO (-3210 1360);
FORCEPROP 0 LASTPIN (-2400 1350) $PN 3
J 0
(-2390 1360);
DISPLAY 0.489362 (-2390 1360);
PAINT MONO (-2390 1360);
FORCEPROP 0 LASTPIN (-2400 1600) $PN 4
J 0
(-2390 1610);
DISPLAY 0.489362 (-2390 1610);
PAINT MONO (-2390 1610);
FORCEPROP 2 LAST PART_TYPE SMLF
J 0
(-3025 1825);
DISPLAY 1.021277 (-3025 1825);
FORCEPROP 1 LAST MATERIAL IND
J 0
(-3025 1685);
DISPLAY 0.489362 (-3025 1685);
PAINT SKYBLUE (-3025 1685);
FORCEPROP 2 LAST VALUE 150NH
J 0
(-3025 1775);
DISPLAY 0.489362 (-3025 1775);
PAINT SKYBLUE (-3025 1775);
FORCEPROP 1 LAST PART_NUMBER CV+15^0TZ04
J 0
(-3025 1635);
DISPLAY 0.489362 (-3025 1635);
PAINT SKYBLUE (-3025 1635);
FORCEPROP 2 LAST CDS_LIB pure_quanta
J 0
(-2800 1475);
DISPLAY INVISIBLE (-2800 1475);
FORCEPROP 1 LAST NEEDS_NO_SIZE TRUE
J 0
(-2800 1475);
DISPLAY 0.468085 (-2800 1475);
PAINT GREEN (-2800 1475);
DISPLAY INVISIBLE (-2800 1475);
FORCEPROP 1 LAST PATH I84
J 0
(-2600 1630);
DISPLAY 0.723404 (-2600 1630);
PAINT GREEN (-2600 1630);
DISPLAY INVISIBLE (-2600 1630);
FORCEADD Q_CAP..1
(-3500 1825);
FORCEPROP 1 LAST LOCATION PC561
J 0
(-3450 1950);
DISPLAY 0.489362 (-3450 1950);
PAINT SKYBLUE (-3450 1950);
FORCEPROP 0 LAST $SEC 1
J 0
(-3450 1975);
DISPLAY 0.680851 (-3450 1975);
PAINT MONO (-3450 1975);
DISPLAY INVISIBLE (-3450 1975);
FORCEPROP 0 LAST CDS_SEC 1
J 0
(-3450 1975);
DISPLAY 1.021277 (-3450 1975);
DISPLAY INVISIBLE (-3450 1975);
FORCEPROP 1 LASTPIN (-3500 1925) $PN 1
J 0
(-3490 1905);
DISPLAY 0.489362 (-3490 1905);
PAINT MONO (-3490 1905);
FORCEPROP 1 LASTPIN (-3500 1725) $PN 2
J 0
(-3490 1705);
DISPLAY 0.489362 (-3490 1705);
PAINT MONO (-3490 1705);
FORCEPROP 1 LAST MATERIAL X7R
J 0
(-3450 1750);
DISPLAY 0.489362 (-3450 1750);
PAINT SKYBLUE (-3450 1750);
FORCEPROP 1 LAST TOLERANCE 10%
J 0
(-3450 1800);
DISPLAY 0.489362 (-3450 1800);
PAINT SKYBLUE (-3450 1800);
FORCEPROP 1 LAST VALUE 0.22UF
J 0
(-3450 1900);
DISPLAY 0.489362 (-3450 1900);
PAINT SKYBLUE (-3450 1900);
FORCEPROP 1 LAST PART_NUMBER CH4223K1B00
J 0
(-3450 1700);
DISPLAY 0.489362 (-3450 1700);
PAINT SKYBLUE (-3450 1700);
FORCEPROP 1 LAST VOLTAGE 16V
J 0
(-3450 1850);
DISPLAY 0.489362 (-3450 1850);
PAINT SKYBLUE (-3450 1850);
FORCEPROP 1 LAST PACK_TYPE 0402
J 0
(-3450 1650);
DISPLAY 0.489362 (-3450 1650);
PAINT SKYBLUE (-3450 1650);
FORCEPROP 2 LAST CDS_LIB pure_quanta
J 0
(-3500 1825);
DISPLAY INVISIBLE (-3500 1825);
FORCEPROP 1 LAST PATH I85
J 0
(-3450 1975);
DISPLAY 0.978723 (-3450 1975);
PAINT WHITE (-3450 1975);
DISPLAY INVISIBLE (-3450 1975);
FORCEADD Q_CAP..1
(-4175 2500);
FORCEPROP 1 LAST LOCATION PC557_4
J 0
(-4125 2600);
DISPLAY 0.489362 (-4125 2600);
PAINT SKYBLUE (-4125 2600);
FORCEPROP 0 LAST $SEC 1
J 0
(-4125 2625);
DISPLAY 0.680851 (-4125 2625);
PAINT MONO (-4125 2625);
DISPLAY INVISIBLE (-4125 2625);
FORCEPROP 0 LAST CDS_SEC 1
J 0
(-4125 2625);
DISPLAY 1.021277 (-4125 2625);
DISPLAY INVISIBLE (-4125 2625);
FORCEPROP 1 LASTPIN (-4175 2600) $PN 1
J 0
(-4165 2580);
DISPLAY 0.489362 (-4165 2580);
PAINT MONO (-4165 2580);
FORCEPROP 1 LASTPIN (-4175 2400) $PN 2
J 0
(-4165 2380);
DISPLAY 0.489362 (-4165 2380);
PAINT MONO (-4165 2380);
FORCEPROP 1 LAST MATERIAL X6S
J 0
(-4125 2400);
DISPLAY 0.489362 (-4125 2400);
PAINT SKYBLUE (-4125 2400);
FORCEPROP 1 LAST TOLERANCE 10%
J 0
(-4125 2450);
DISPLAY 0.489362 (-4125 2450);
PAINT SKYBLUE (-4125 2450);
FORCEPROP 1 LAST VALUE 10UF
J 0
(-4125 2550);
DISPLAY 0.489362 (-4125 2550);
PAINT SKYBLUE (-4125 2550);
FORCEPROP 1 LAST PART_NUMBER CH6104KEA00
J 0
(-4125 2350);
DISPLAY 0.489362 (-4125 2350);
PAINT SKYBLUE (-4125 2350);
FORCEPROP 1 LAST VOLTAGE 25V
J 0
(-4125 2500);
DISPLAY 0.489362 (-4125 2500);
PAINT SKYBLUE (-4125 2500);
FORCEPROP 1 LAST PACK_TYPE C0805
J 0
(-4125 2300);
DISPLAY 0.489362 (-4125 2300);
PAINT SKYBLUE (-4125 2300);
FORCEPROP 2 LAST CDS_LIB pure_quanta
J 0
(-4175 2500);
DISPLAY INVISIBLE (-4175 2500);
FORCEPROP 1 LAST PATH I86
J 0
(-4125 2650);
DISPLAY 0.978723 (-4125 2650);
PAINT WHITE (-4125 2650);
DISPLAY INVISIBLE (-4125 2650);
FORCEADD Q_CAP..1
(-4500 2500);
FORCEPROP 1 LAST LOCATION PC555_4
J 0
(-4450 2600);
DISPLAY 0.489362 (-4450 2600);
PAINT SKYBLUE (-4450 2600);
FORCEPROP 0 LAST $SEC 1
J 0
(-4450 2625);
DISPLAY 0.680851 (-4450 2625);
PAINT MONO (-4450 2625);
DISPLAY INVISIBLE (-4450 2625);
FORCEPROP 0 LAST CDS_SEC 1
J 0
(-4450 2625);
DISPLAY 1.021277 (-4450 2625);
DISPLAY INVISIBLE (-4450 2625);
FORCEPROP 1 LASTPIN (-4500 2600) $PN 1
J 0
(-4490 2580);
DISPLAY 0.489362 (-4490 2580);
PAINT MONO (-4490 2580);
FORCEPROP 1 LASTPIN (-4500 2400) $PN 2
J 0
(-4490 2380);
DISPLAY 0.489362 (-4490 2380);
PAINT MONO (-4490 2380);
FORCEPROP 1 LAST MATERIAL X6S
J 0
(-4450 2400);
DISPLAY 0.489362 (-4450 2400);
PAINT SKYBLUE (-4450 2400);
FORCEPROP 1 LAST TOLERANCE 10%
J 0
(-4450 2450);
DISPLAY 0.489362 (-4450 2450);
PAINT SKYBLUE (-4450 2450);
FORCEPROP 1 LAST VALUE 10UF
J 0
(-4450 2550);
DISPLAY 0.489362 (-4450 2550);
PAINT SKYBLUE (-4450 2550);
FORCEPROP 1 LAST PART_NUMBER CH6104KEA00
J 0
(-4450 2350);
DISPLAY 0.489362 (-4450 2350);
PAINT SKYBLUE (-4450 2350);
FORCEPROP 1 LAST VOLTAGE 25V
J 0
(-4450 2500);
DISPLAY 0.489362 (-4450 2500);
PAINT SKYBLUE (-4450 2500);
FORCEPROP 1 LAST PACK_TYPE C0805
J 0
(-4450 2300);
DISPLAY 0.489362 (-4450 2300);
PAINT SKYBLUE (-4450 2300);
FORCEPROP 2 LAST CDS_LIB pure_quanta
J 0
(-4500 2500);
DISPLAY INVISIBLE (-4500 2500);
FORCEPROP 1 LAST PATH I87
J 0
(-4450 2650);
DISPLAY 0.978723 (-4450 2650);
PAINT WHITE (-4450 2650);
DISPLAY INVISIBLE (-4450 2650);
FORCEADD Q_CAP..1
(-4825 2500);
FORCEPROP 1 LAST LOCATION PC553_4
J 0
(-4775 2600);
DISPLAY 0.489362 (-4775 2600);
PAINT SKYBLUE (-4775 2600);
FORCEPROP 0 LAST $SEC 1
J 0
(-4775 2625);
DISPLAY 0.680851 (-4775 2625);
PAINT MONO (-4775 2625);
DISPLAY INVISIBLE (-4775 2625);
FORCEPROP 0 LAST CDS_SEC 1
J 0
(-4775 2625);
DISPLAY 1.021277 (-4775 2625);
DISPLAY INVISIBLE (-4775 2625);
FORCEPROP 1 LASTPIN (-4825 2600) $PN 1
J 0
(-4815 2580);
DISPLAY 0.489362 (-4815 2580);
PAINT MONO (-4815 2580);
FORCEPROP 1 LASTPIN (-4825 2400) $PN 2
J 0
(-4815 2380);
DISPLAY 0.489362 (-4815 2380);
PAINT MONO (-4815 2380);
FORCEPROP 1 LAST MATERIAL X6S
J 0
(-4775 2400);
DISPLAY 0.489362 (-4775 2400);
PAINT SKYBLUE (-4775 2400);
FORCEPROP 1 LAST TOLERANCE 10%
J 0
(-4775 2450);
DISPLAY 0.489362 (-4775 2450);
PAINT SKYBLUE (-4775 2450);
FORCEPROP 1 LAST VALUE 1UF
J 0
(-4775 2550);
DISPLAY 0.489362 (-4775 2550);
PAINT SKYBLUE (-4775 2550);
FORCEPROP 1 LAST PART_NUMBER CH5104KEB02
J 0
(-4775 2350);
DISPLAY 0.489362 (-4775 2350);
PAINT SKYBLUE (-4775 2350);
FORCEPROP 1 LAST VOLTAGE 25V
J 0
(-4775 2500);
DISPLAY 0.489362 (-4775 2500);
PAINT SKYBLUE (-4775 2500);
FORCEPROP 1 LAST PACK_TYPE C0402
J 0
(-4775 2300);
DISPLAY 0.489362 (-4775 2300);
PAINT SKYBLUE (-4775 2300);
FORCEPROP 2 LAST CDS_LIB pure_quanta
J 0
(-4825 2500);
DISPLAY INVISIBLE (-4825 2500);
FORCEPROP 1 LAST PATH I88
J 0
(-4775 2650);
DISPLAY 0.978723 (-4775 2650);
PAINT WHITE (-4775 2650);
DISPLAY INVISIBLE (-4775 2650);
FORCEADD Q_RES..1
(-4475 1950);
FORCEPROP 1 LAST LOCATION PR349
J 0
(-4500 2000);
DISPLAY 0.489362 (-4500 2000);
PAINT SKYBLUE (-4500 2000);
FORCEPROP 0 LAST $SEC 1
J 0
(-4450 2025);
DISPLAY 0.680851 (-4450 2025);
PAINT MONO (-4450 2025);
DISPLAY INVISIBLE (-4450 2025);
FORCEPROP 0 LAST CDS_SEC 1
J 0
(-4450 2025);
DISPLAY 1.021277 (-4450 2025);
DISPLAY INVISIBLE (-4450 2025);
FORCEPROP 1 LASTPIN (-4575 1950) $PN 1
J 0
(-4563 1962);
DISPLAY 0.489362 (-4563 1962);
PAINT MONO (-4563 1962);
FORCEPROP 1 LASTPIN (-4375 1950) $PN 2
J 0
(-4413 1962);
DISPLAY 0.489362 (-4413 1962);
PAINT MONO (-4413 1962);
FORCEPROP 1 LAST PACK_TYPE 0402LF
J 0
(-4375 1850);
DISPLAY 0.489362 (-4375 1850);
PAINT SKYBLUE (-4375 1850);
FORCEPROP 1 LAST TOLERANCE 1%
J 0
(-4375 1975);
DISPLAY 0.489362 (-4375 1975);
PAINT SKYBLUE (-4375 1975);
FORCEPROP 1 LAST MATERIAL CHIP
J 0
(-4725 1850);
DISPLAY 0.489362 (-4725 1850);
PAINT SKYBLUE (-4725 1850);
FORCEPROP 1 LAST WATTAGE 1/16W
J 0
(-4375 1900);
DISPLAY 0.489362 (-4375 1900);
PAINT SKYBLUE (-4375 1900);
FORCEPROP 1 LAST VALUE 4.7
J 2
(-4575 1975);
DISPLAY 0.489362 (-4575 1975);
PAINT SKYBLUE (-4575 1975);
FORCEPROP 1 LAST PART_NUMBER CS-4702FB19
J 0
(-4725 1900);
DISPLAY 0.489362 (-4725 1900);
PAINT SKYBLUE (-4725 1900);
FORCEPROP 1 LAST PATH I89
J 0
(-4525 2100);
DISPLAY 0.978723 (-4525 2100);
PAINT WHITE (-4525 2100);
DISPLAY INVISIBLE (-4525 2100);
FORCEPROP 2 LAST CDS_LIB pure_quanta
J 0
(-4475 1950);
DISPLAY INVISIBLE (-4475 1950);
FORCEADD Q_RES..1
(-3975 700);
FORCEPROP 1 LAST LOCATION PR351
J 0
(-4000 750);
DISPLAY 0.489362 (-4000 750);
PAINT SKYBLUE (-4000 750);
FORCEPROP 0 LAST $SEC 1
J 0
(-3975 775);
DISPLAY 0.680851 (-3975 775);
PAINT MONO (-3975 775);
DISPLAY INVISIBLE (-3975 775);
FORCEPROP 0 LAST CDS_SEC 1
J 0
(-3975 775);
DISPLAY 1.021277 (-3975 775);
DISPLAY INVISIBLE (-3975 775);
FORCEPROP 1 LASTPIN (-4075 700) $PN 1
J 0
(-4063 712);
DISPLAY 0.489362 (-4063 712);
PAINT MONO (-4063 712);
FORCEPROP 1 LASTPIN (-3875 700) $PN 2
J 0
(-3913 712);
DISPLAY 0.489362 (-3913 712);
PAINT MONO (-3913 712);
FORCEPROP 1 LAST WATTAGE 1/16W
J 0
(-3875 650);
DISPLAY 0.489362 (-3875 650);
PAINT SKYBLUE (-3875 650);
FORCEPROP 1 LAST MATERIAL CHIP
J 0
(-4225 600);
DISPLAY 0.489362 (-4225 600);
PAINT SKYBLUE (-4225 600);
FORCEPROP 1 LAST TOLERANCE 5%
J 0
(-3850 725);
DISPLAY 0.489362 (-3850 725);
PAINT SKYBLUE (-3850 725);
FORCEPROP 1 LAST VALUE 0
J 2
(-4100 725);
DISPLAY 0.489362 (-4100 725);
PAINT SKYBLUE (-4100 725);
FORCEPROP 1 LAST PART_NUMBER CS00002JB38
J 0
(-4225 650);
DISPLAY 0.489362 (-4225 650);
PAINT SKYBLUE (-4225 650);
FORCEPROP 1 LAST PACK_TYPE 0402LF
J 0
(-3875 600);
DISPLAY 0.489362 (-3875 600);
PAINT SKYBLUE (-3875 600);
FORCEPROP 2 LAST CDS_LIB pure_quanta
J 0
(-3975 700);
DISPLAY INVISIBLE (-3975 700);
FORCEPROP 1 LAST PATH I90
J 0
(-4025 850);
DISPLAY 0.978723 (-4025 850);
PAINT WHITE (-4025 850);
DISPLAY INVISIBLE (-4025 850);
FORCEADD UNIVERSAL_GND..1
(-5325 850);
FORCEPROP 3 LASTPIN (-5325 900) SIG_NAME GND\g
J 0
(-5315 910);
DISPLAY 0.659574 (-5315 910);
PAINT MONO (-5315 910);
DISPLAY INVISIBLE (-5315 910);
FORCEPROP 2 LAST CDS_LIB pure_quanta_power
J 0
(-5325 850);
DISPLAY INVISIBLE (-5325 850);
FORCEPROP 1 LAST PATH I92
J 0
(-5250 850);
DISPLAY 0.872340 (-5250 850);
PAINT AQUA (-5250 850);
DISPLAY INVISIBLE (-5250 850);
FORCEPROP 1 LAST HDL_POWER GND
J 1
(-5300 775);
DISPLAY 0.872340 (-5300 775);
PAINT GREEN (-5300 775);
DISPLAY INVISIBLE (-5300 775);
FORCEADD Q_RES..1
(-7050 1300);
FORCEPROP 1 LAST LOCATION PR347
J 0
(-7100 1350);
DISPLAY 0.489362 (-7100 1350);
PAINT SKYBLUE (-7100 1350);
FORCEPROP 0 LAST $SEC 1
J 0
(-7050 1375);
DISPLAY 0.680851 (-7050 1375);
PAINT MONO (-7050 1375);
DISPLAY INVISIBLE (-7050 1375);
FORCEPROP 0 LAST CDS_SEC 1
J 0
(-7050 1375);
DISPLAY 1.021277 (-7050 1375);
DISPLAY INVISIBLE (-7050 1375);
FORCEPROP 1 LASTPIN (-7150 1300) $PN 1
J 0
(-7138 1312);
DISPLAY 0.489362 (-7138 1312);
PAINT MONO (-7138 1312);
FORCEPROP 1 LASTPIN (-6950 1300) $PN 2
J 0
(-6988 1312);
DISPLAY 0.489362 (-6988 1312);
PAINT MONO (-6988 1312);
FORCEPROP 1 LAST WATTAGE 1/16W
J 0
(-6950 1200);
DISPLAY 0.489362 (-6950 1200);
PAINT SKYBLUE (-6950 1200);
FORCEPROP 1 LAST MATERIAL EMPTY
J 0
(-7350 1200);
DISPLAY 0.489362 (-7350 1200);
PAINT RED (-7350 1200);
FORCEPROP 1 LAST TOLERANCE 1%
J 0
(-6925 1325);
DISPLAY 0.489362 (-6925 1325);
PAINT SKYBLUE (-6925 1325);
FORCEPROP 1 LAST VALUE 8.87K
J 2
(-7175 1325);
DISPLAY 0.489362 (-7175 1325);
PAINT SKYBLUE (-7175 1325);
FORCEPROP 1 LAST PART_NUMBER CS28872FB01
J 0
(-7350 1250);
DISPLAY 0.489362 (-7350 1250);
PAINT SKYBLUE (-7350 1250);
FORCEPROP 1 LAST PACK_TYPE 0402LF
J 0
(-6950 1250);
DISPLAY 0.489362 (-6950 1250);
PAINT SKYBLUE (-6950 1250);
FORCEPROP 2 LAST CDS_LIB pure_quanta
J 0
(-7050 1300);
DISPLAY INVISIBLE (-7050 1300);
FORCEPROP 1 LAST PATH I96
J 0
(-7100 1450);
DISPLAY 0.978723 (-7100 1450);
PAINT WHITE (-7100 1450);
DISPLAY INVISIBLE (-7100 1450);
FORCEADD OFFPAGE..2
R 2
(-7025 1600);
FORCEPROP 2 LAST $XR0 169 
J 0
(-7280 1600);
DISPLAY 0.638298 (-7280 1600);
PAINT MONO (-7280 1600);
FORCEPROP 2 LAST PATH I99
J 0
(-6975 1675);
DISPLAY 1.021277 (-6975 1675);
DISPLAY INVISIBLE (-6975 1675);
FORCEPROP 1 LAST COMMENT_BODY TRUE
J 2
(-6980 1505);
DISPLAY 0.872340 (-6980 1505);
PAINT GREEN (-6980 1505);
DISPLAY INVISIBLE (-6980 1505);
FORCEPROP 1 LAST OFFPAGE TRUE
J 2
(-7350 1475);
DISPLAY 0.872340 (-7350 1475);
PAINT GREEN (-7350 1475);
DISPLAY INVISIBLE (-7350 1475);
FORCEPROP 2 LAST CDS_LIB standard
J 2
(-7025 1600);
DISPLAY INVISIBLE (-7025 1600);
FORCEADD DNS..1
(-7050 1275);
PAINT RED (-7050 1275);
FORCEPROP 2 LAST CDS_LIB mstr_misc
J 0
(-7050 1275);
DISPLAY INVISIBLE (-7050 1275);
FORCEPROP 1 LAST COMMENT_BODY TRUE
R 1
J 0
(-6975 1050);
DISPLAY 0.872340 (-6975 1050);
PAINT GREEN (-6975 1050);
DISPLAY INVISIBLE (-6975 1050);
FORCEADD DNS..1
(-4425 975);
PAINT RED (-4425 975);
FORCEPROP 2 LAST CDS_LIB mstr_misc
J 0
(-4425 975);
DISPLAY INVISIBLE (-4425 975);
FORCEPROP 1 LAST COMMENT_BODY TRUE
R 1
J 0
(-4350 750);
DISPLAY 0.872340 (-4350 750);
PAINT GREEN (-4350 750);
DISPLAY INVISIBLE (-4350 750);
FORCEADD QUANTA_TITLE_BLOCK_C..1
(0 0);
FORCEPROP 0 LAST CDS_CON_LAST_MODIFIED Fri Mar 11 14:53:25 2022
J 0
(-1885 15);
DISPLAY INVISIBLE (-1885 15);
FORCEPROP 1 LAST CUSTOM_TXT_CDS <CON_LAST_MODIFIED>
J 0
(-1885 15);
DISPLAY 0.978723 (-1885 15);
FORCEPROP 2 LAST CUSTOM_TXT_CDS <XR_PAGE_TITLE>
J 0
(-7890 5250);
DISPLAY 0.638298 (-7890 5250);
PAINT PINK (-7890 5250);
DISPLAY INVISIBLE (-7890 5250);
FORCEPROP 1 LAST CUSTOM_TXT_CDS <NAME_2>
J 0
(-3175 50);
FORCEPROP 1 LAST CUSTOM_TXT_CDS <NAME_1>
J 0
(-3175 175);
FORCEPROP 1 LAST CUSTOM_TXT_CDS <Q_NUMBER>
J 0
(-1403 103);
DISPLAY 1.212766 (-1403 103);
FORCEPROP 1 LAST CUSTOM_TXT_CDS <Q_PROJ>
J 0
(-2382 102);
DISPLAY 1.212766 (-2382 102);
FORCEPROP 1 LAST CUSTOM_TXT_CDS <Q_REV>
J 0
(-184 103);
DISPLAY 1.212766 (-184 103);
FORCEPROP 1 LAST CUSTOM_TXT_CDS <CON_PAGE_NUM> OF <CON_TOTAL_PAGES>
J 0
(-446 18);
DISPLAY 0.978723 (-446 18);
FORCEPROP 1 LAST Q_DEPT BU9
J 1
(-3763 49);
DISPLAY 1.957447 (-3763 49);
PAINT GREEN (-3763 49);
FORCEPROP 1 LAST Q_TITLE PVDDCR_CPU0_P0 VR PHASE 3&4
J 0
(-9325 50);
DISPLAY 2.446809 (-9325 50);
PAINT GREEN (-9325 50);
FORCEPROP 1 LAST CDS_LMAN_SYM_OUTLINE -9475,6775,100,-125
J 0
(0 0);
DISPLAY 0.468085 (0 0);
PAINT GREEN (0 0);
DISPLAY INVISIBLE (0 0);
FORCEPROP 2 LAST CDS_LIB pure_quanta
J 0
(0 0);
DISPLAY INVISIBLE (0 0);
FORCEPROP 2 LAST PAGE_BORDER TRUE
J 0
(-7890 5250);
DISPLAY 0.638298 (-7890 5250);
PAINT PINK (-7890 5250);
DISPLAY INVISIBLE (-7890 5250);
FORCEPROP 1 LAST COMMENT_BODY TRUE
J 0
(12 -13);
DISPLAY 0.978723 (12 -13);
PAINT GREEN (12 -13);
DISPLAY INVISIBLE (12 -13);
FORCEPROP 2 LAST CDS_XR_PAGE_TITLE CR-171 : @T6G_MB_LIB.T6G(SCH_1):PAGE171
J 0
(-7890 5250);
DISPLAY 0.638298 (-7890 5250);
PAINT PINK (-7890 5250);
DISPLAY INVISIBLE (-7890 5250);
FORCEADD DNS..1
(-7125 4575);
PAINT RED (-7125 4575);
FORCEPROP 2 LAST CDS_LIB mstr_misc
J 0
(-7125 4575);
DISPLAY INVISIBLE (-7125 4575);
FORCEPROP 1 LAST COMMENT_BODY TRUE
R 1
J 0
(-7050 4350);
DISPLAY 0.872340 (-7050 4350);
PAINT GREEN (-7050 4350);
DISPLAY INVISIBLE (-7050 4350);
FORCEADD DNS..1
(-4500 4725);
PAINT RED (-4500 4725);
FORCEPROP 2 LAST CDS_LIB mstr_misc
J 0
(-4500 4725);
DISPLAY INVISIBLE (-4500 4725);
FORCEPROP 1 LAST COMMENT_BODY TRUE
R 1
J 0
(-4425 4500);
DISPLAY 0.872340 (-4425 4500);
PAINT GREEN (-4425 4500);
DISPLAY INVISIBLE (-4425 4500);
FORCEADD DNS..1
(-4425 1425);
PAINT RED (-4425 1425);
FORCEPROP 2 LAST CDS_LIB mstr_misc
J 0
(-4425 1425);
DISPLAY INVISIBLE (-4425 1425);
FORCEPROP 1 LAST COMMENT_BODY TRUE
R 1
J 0
(-4350 1200);
DISPLAY 0.872340 (-4350 1200);
PAINT GREEN (-4350 1200);
DISPLAY INVISIBLE (-4350 1200);
FORCEADD DNS..1
(-4500 4250);
PAINT RED (-4500 4250);
FORCEPROP 2 LAST CDS_LIB mstr_misc
J 0
(-4500 4250);
DISPLAY INVISIBLE (-4500 4250);
FORCEPROP 1 LAST COMMENT_BODY TRUE
R 1
J 0
(-4425 4025);
DISPLAY 0.872340 (-4425 4025);
PAINT GREEN (-4425 4025);
DISPLAY INVISIBLE (-4425 4025);
WIRE 16 -1 (-7775 4525)(-7775 4400);
WIRE 16 -1 (-7150 1300)(-7375 1300);
WIRE 16 -1 (-7375 1300)(-7375 1175);
WIRE 16 -1 (-7700 1225)(-7700 1100);
WIRE 16 -1 (-7450 5150)(-7450 5100);
WIRE 16 -1 (-7100 5650)(-7100 5550);
WIRE 16 -1 (-7350 1850)(-7350 1800);
WIRE 16 -1 (-7000 2425)(-7000 2300);
WIRE 16 -1 (-4475 4150)(-4475 4075);
WIRE 16 -1 (-4400 875)(-4400 800);
WIRE 16 -1 (-7225 4600)(-7450 4600);
WIRE 16 -1 (-7450 4600)(-7450 4475);
WIRE 16 -1 (-4375 1950)(-3500 1950);
FORCEPROP 2 LAST SIG_NAME SW_PVDDCR_CPU0_P0_BOOT4_RC
J 2
(-3535 1960);
DISPLAY 0.489362 (-3535 1960);
FORCEPROP 2 LASTPROP $XRERR UNIQUE?
J 0
(-3775 1960);
DISPLAY 0.638298 (-3775 1960);
PAINT MONO (-3775 1960);
DISPLAY INVISIBLE (-3775 1960);
WIRE 16 -1 (-3500 1950)(-3500 1925);
WIRE 16 -1 (-3800 2400)(-3800 2275);
WIRE 16 -1 (-3800 2275)(-3800 2200);
WIRE 16 -1 (-4175 2275)(-3800 2275);
WIRE 16 -1 (-4175 2400)(-4175 2275);
WIRE 16 -1 (-4500 2275)(-4175 2275);
WIRE 16 -1 (-4500 2400)(-4500 2275);
WIRE 16 -1 (-4825 2275)(-4500 2275);
WIRE 16 -1 (-4825 2400)(-4825 2275);
WIRE 16 -1 (-5200 2275)(-4825 2275);
WIRE 16 -1 (-5200 2400)(-5200 2275);
WIRE 16 -1 (-5475 1600)(-4400 1600);
FORCEPROP 2 LAST SIG_NAME SW_PVDDCR_CPU0_P0_SW4
J 0
(-5360 1610);
DISPLAY 0.489362 (-5360 1610);
FORCEPROP 2 LASTPROP $XRERR UNIQUE?
J 0
(-5600 1610);
DISPLAY 0.638298 (-5600 1610);
PAINT MONO (-5600 1610);
DISPLAY INVISIBLE (-5600 1610);
WIRE 16 -1 (-3200 1600)(-4400 1600);
WIRE 16 -1 (-4400 1600)(-4400 1525);
WIRE 16 -1 (-3500 1725)(-3500 1700);
WIRE 16 -1 (-3500 1700)(-5475 1700);
FORCEPROP 2 LAST SIG_NAME SW_PVDDCR_CPU0_P0_PH4
J 0
(-5360 1710);
DISPLAY 0.489362 (-5360 1710);
FORCEPROP 2 LASTPROP $XRERR UNIQUE?
J 0
(-5600 1710);
DISPLAY 0.638298 (-5600 1710);
PAINT MONO (-5600 1710);
DISPLAY INVISIBLE (-5600 1710);
WIRE 16 -1 (-3550 5025)(-3550 5000);
WIRE 16 -1 (-3550 5000)(-5550 5000);
FORCEPROP 2 LAST SIG_NAME SW_PVDDCR_CPU0_P0_PH3
J 0
(-5435 5010);
DISPLAY 0.489362 (-5435 5010);
FORCEPROP 2 LASTPROP $XRERR UNIQUE?
J 0
(-5675 5010);
DISPLAY 0.638298 (-5675 5010);
PAINT MONO (-5675 5010);
DISPLAY INVISIBLE (-5675 5010);
WIRE 16 -1 (-5550 5250)(-4650 5250);
FORCEPROP 2 LAST SIG_NAME SW_PVDDCR_CPU0_P0_BOOT3
J 0
(-5435 5260);
DISPLAY 0.489362 (-5435 5260);
FORCEPROP 2 LASTPROP $XRERR UNIQUE?
J 0
(-5675 5260);
DISPLAY 0.638298 (-5675 5260);
PAINT MONO (-5675 5260);
DISPLAY INVISIBLE (-5675 5260);
WIRE 16 -1 (-4025 5700)(-4025 5575);
WIRE 16 -1 (-4025 5575)(-4025 5525);
WIRE 16 -1 (-4025 5575)(-4325 5575);
WIRE 16 -1 (-4325 5700)(-4325 5575);
WIRE 16 -1 (-4650 5575)(-4325 5575);
WIRE 16 -1 (-4650 5700)(-4650 5575);
WIRE 16 -1 (-4975 5575)(-4650 5575);
WIRE 16 -1 (-4975 5700)(-4975 5575);
WIRE 16 -1 (-5325 5575)(-4975 5575);
WIRE 16 -1 (-5325 5700)(-5325 5575);
WIRE 16 -1 (-5550 4900)(-4475 4900);
FORCEPROP 2 LAST SIG_NAME SW_PVDDCR_CPU0_P0_SW3
J 0
(-5435 4910);
DISPLAY 0.489362 (-5435 4910);
FORCEPROP 2 LASTPROP $XRERR UNIQUE?
J 0
(-5675 4910);
DISPLAY 0.638298 (-5675 4910);
PAINT MONO (-5675 4910);
DISPLAY INVISIBLE (-5675 4910);
WIRE 16 -1 (-4475 4900)(-3225 4900);
WIRE 16 -1 (-4475 4900)(-4475 4825);
WIRE 16 -1 (-7875 1500)(-7700 1500);
WIRE 16 -1 (-6325 1500)(-7700 1500);
FORCEPROP 2 LAST SIG_NAME PVDDCR_CPU0_P0_VCCS
J 2
(-6385 1510);
DISPLAY 0.489362 (-6385 1510);
WIRE 16 -1 (-7700 1425)(-7700 1500);
WIRE 16 -1 (-6325 1000)(-6925 1000);
FORCEPROP 2 LAST SIG_NAME PVDDCR_CPU0_P0_PWM4
J 2
(-6385 1010);
DISPLAY 0.489362 (-6385 1010);
WIRE 16 -1 (-6950 1300)(-6325 1300);
FORCEPROP 2 LAST SIG_NAME PVDDCR_CPU0_P0_LSET4
J 2
(-6385 1310);
DISPLAY 0.489362 (-6385 1310);
FORCEPROP 2 LASTPROP $XRERR UNIQUE?
J 0
(-6625 1310);
DISPLAY 0.638298 (-6625 1310);
PAINT MONO (-6625 1310);
DISPLAY INVISIBLE (-6625 1310);
WIRE 16 -1 (-6325 1350)(-6775 1350);
FORCEPROP 2 LAST SIG_NAME NC_PVDDCR_CPU0_P0_DNC4
J 2
(-6385 1360);
DISPLAY 0.489362 (-6385 1360);
FORCEPROP 2 LASTPROP $XRERR UNIQUE?
J 0
(-7015 1350);
DISPLAY 0.638298 (-7015 1350);
PAINT MONO (-7015 1350);
DISPLAY INVISIBLE (-7015 1350);
WIRE 16 -1 (-6900 1750)(-6325 1750);
WIRE 16 -1 (-6900 1950)(-6900 1750);
WIRE 16 -1 (-6900 2125)(-6900 1950);
FORCEPROP 2 LAST SIG_NAME PVDDCR_CPU0_P0_VCC4
J 2
(-6435 1960);
DISPLAY 0.489362 (-6435 1960);
FORCEPROP 2 LASTPROP $XRERR UNIQUE?
J 0
(-6675 1960);
DISPLAY 0.638298 (-6675 1960);
PAINT MONO (-6675 1960);
DISPLAY INVISIBLE (-6675 1960);
WIRE 16 -1 (-6900 1950)(-6325 1950);
WIRE 16 -1 (-7350 2125)(-6900 2125);
WIRE 16 -1 (-7350 2400)(-7350 2125);
WIRE 16 -1 (-7350 2125)(-7350 2050);
WIRE 16 -1 (-6325 1100)(-6950 1100);
FORCEPROP 2 LAST SIG_NAME PVDDCR_CPU0_P0_TEMP0
J 2
(-6385 1110);
DISPLAY 0.489362 (-6385 1110);
WIRE 16 -1 (-6325 1600)(-6975 1600);
FORCEPROP 2 LAST SIG_NAME PVDDCR_CPU0_P0_IMON4
J 2
(-6385 1610);
DISPLAY 0.489362 (-6385 1610);
WIRE 16 -1 (-7350 2600)(-7350 2725);
WIRE 16 -1 (-7000 2725)(-7350 2725);
WIRE 16 -1 (-7350 2850)(-7350 2725);
WIRE 16 -1 (-6675 2725)(-7000 2725);
WIRE 16 -1 (-7000 2625)(-7000 2725);
WIRE 16 -1 (-6675 2250)(-6675 2725);
WIRE 16 -1 (-6675 2250)(-6325 2250);
WIRE 16 -1 (-5475 1000)(-5325 1000);
WIRE 16 -1 (-5325 1000)(-5325 1050);
WIRE 16 -1 (-5325 900)(-5325 1000);
WIRE 16 -1 (-5325 1050)(-5325 1100);
WIRE 16 -1 (-5475 1050)(-5325 1050);
WIRE 16 -1 (-5475 1100)(-5325 1100);
WIRE 16 -1 (-5325 1150)(-5325 1100);
WIRE 16 -1 (-5325 1150)(-5475 1150);
WIRE 16 -1 (-5475 1250)(-4950 1250);
FORCEPROP 2 LAST SIG_NAME NC_PVDDCR_CPU0_P0_GL2_4
J 0
(-5360 1260);
DISPLAY 0.489362 (-5360 1260);
FORCEPROP 2 LASTPROP $XRERR UNIQUE?
J 0
(-4920 1250);
DISPLAY 0.638298 (-4920 1250);
PAINT MONO (-4920 1250);
DISPLAY INVISIBLE (-4920 1250);
WIRE 16 -1 (-5475 1300)(-4950 1300);
FORCEPROP 2 LAST SIG_NAME NC_PVDDCR_CPU0_P0_GL1_4
J 0
(-5360 1310);
DISPLAY 0.489362 (-5360 1310);
FORCEPROP 2 LASTPROP $XRERR UNIQUE?
J 0
(-4920 1300);
DISPLAY 0.638298 (-4920 1300);
PAINT MONO (-4920 1300);
DISPLAY INVISIBLE (-4920 1300);
WIRE 16 -1 (-5475 1950)(-4575 1950);
FORCEPROP 2 LAST SIG_NAME SW_PVDDCR_CPU0_P0_BOOT4
J 0
(-5360 1960);
DISPLAY 0.489362 (-5360 1960);
FORCEPROP 2 LASTPROP $XRERR UNIQUE?
J 0
(-5600 1960);
DISPLAY 0.638298 (-5600 1960);
PAINT MONO (-5600 1960);
DISPLAY INVISIBLE (-5600 1960);
WIRE 16 -1 (-5475 1350)(-4725 1350);
WIRE 16 -1 (-4725 700)(-4725 1350);
WIRE 16 -1 (-4075 700)(-4725 700);
FORCEPROP 2 LAST SIG_NAME PVDDCR_CPU0_P0_VOS4
J 0
(-5360 1375);
DISPLAY 0.489362 (-5360 1375);
FORCEPROP 2 LASTPROP $XRERR UNIQUE?
J 0
(-5600 1375);
DISPLAY 0.638298 (-5600 1375);
PAINT MONO (-5600 1375);
DISPLAY INVISIBLE (-5600 1375);
WIRE 16 -1 (-4400 1325)(-4400 1075);
FORCEPROP 2 LAST SIG_NAME SW_PVDDCR_CPU0_P0_SW4_RC
J 0
(-4360 1160);
DISPLAY 0.489362 (-4360 1160);
FORCEPROP 2 LASTPROP $XRERR UNIQUE?
J 0
(-4600 1160);
DISPLAY 0.638298 (-4600 1160);
PAINT MONO (-4600 1160);
DISPLAY INVISIBLE (-4600 1160);
WIRE 16 -1 (-5375 2250)(-5375 2200);
WIRE 16 -1 (-5475 2250)(-5375 2250);
WIRE 16 -1 (-5375 2675)(-5375 2250);
WIRE 16 -1 (-5375 2200)(-5475 2200);
WIRE 16 -1 (-5375 2675)(-5200 2675);
WIRE 16 -1 (-5200 2675)(-4825 2675);
WIRE 16 -1 (-5200 2600)(-5200 2675);
WIRE 16 -1 (-4825 2675)(-4500 2675);
WIRE 16 -1 (-4825 2600)(-4825 2675);
WIRE 16 -1 (-4500 2675)(-4175 2675);
WIRE 16 -1 (-4500 2600)(-4500 2675);
WIRE 16 -1 (-4175 2675)(-3800 2675);
WIRE 16 -1 (-4175 2675)(-4175 2600);
WIRE 16 -1 (-3800 2750)(-3800 2675);
WIRE 16 -1 (-3800 2675)(-3800 2600);
WIRE 16 -1 (-4250 3950)(-4800 3950);
FORCEPROP 2 LAST SIG_NAME PVDDCR_CPU0_P0_VOS3
J 0
(-5435 4675);
DISPLAY 0.489362 (-5435 4675);
FORCEPROP 2 LASTPROP $XRERR UNIQUE?
J 0
(-5675 4675);
DISPLAY 0.638298 (-5675 4675);
PAINT MONO (-5675 4675);
DISPLAY INVISIBLE (-5675 4675);
WIRE 16 -1 (-4800 3950)(-4800 4650);
WIRE 16 -1 (-5550 4650)(-4800 4650);
WIRE 16 -1 (-7450 5425)(-6950 5425);
WIRE 16 -1 (-7450 5650)(-7450 5425);
WIRE 16 -1 (-7450 5425)(-7450 5350);
WIRE 16 -1 (-6950 5425)(-6950 5250);
FORCEPROP 2 LAST SIG_NAME PVDDCR_CPU0_P0_VCC3
J 2
(-6485 5260);
DISPLAY 0.489362 (-6485 5260);
FORCEPROP 2 LASTPROP $XRERR UNIQUE?
J 0
(-6725 5260);
DISPLAY 0.638298 (-6725 5260);
PAINT MONO (-6725 5260);
DISPLAY INVISIBLE (-6725 5260);
WIRE 16 -1 (-6950 5250)(-6950 5050);
WIRE 16 -1 (-6400 5250)(-6950 5250);
WIRE 16 -1 (-6950 5050)(-6400 5050);
WIRE 16 -1 (-7950 4800)(-7775 4800);
WIRE 16 -1 (-6400 4800)(-7775 4800);
FORCEPROP 2 LAST SIG_NAME PVDDCR_CPU0_P0_VCCS
J 2
(-6485 4810);
DISPLAY 0.489362 (-6485 4810);
WIRE 16 -1 (-7775 4725)(-7775 4800);
WIRE 16 -1 (-6400 4650)(-6850 4650);
FORCEPROP 2 LAST SIG_NAME NC_PVDDCR_CPU0_P0_DNC3
J 2
(-6485 4660);
DISPLAY 0.489362 (-6485 4660);
FORCEPROP 2 LASTPROP $XRERR UNIQUE?
J 0
(-7090 4650);
DISPLAY 0.638298 (-7090 4650);
PAINT MONO (-7090 4650);
DISPLAY INVISIBLE (-7090 4650);
WIRE 16 -1 (-7025 4600)(-6400 4600);
FORCEPROP 2 LAST SIG_NAME PVDDCR_CPU0_P0_LSET3
J 2
(-6485 4610);
DISPLAY 0.489362 (-6485 4610);
FORCEPROP 2 LASTPROP $XRERR UNIQUE?
J 0
(-6725 4610);
DISPLAY 0.638298 (-6725 4610);
PAINT MONO (-6725 4610);
DISPLAY INVISIBLE (-6725 4610);
WIRE 16 -1 (-6400 4900)(-7050 4900);
FORCEPROP 2 LAST SIG_NAME PVDDCR_CPU0_P0_IMON3
J 2
(-6485 4910);
DISPLAY 0.489362 (-6485 4910);
WIRE 16 -1 (-6400 4400)(-7025 4400);
FORCEPROP 2 LAST SIG_NAME PVDDCR_CPU0_P0_TEMP0
J 2
(-6485 4410);
DISPLAY 0.489362 (-6485 4410);
WIRE 16 -1 (-6400 4300)(-7000 4300);
FORCEPROP 2 LAST SIG_NAME PVDDCR_CPU0_P0_PWM3
J 2
(-6485 4310);
DISPLAY 0.489362 (-6485 4310);
WIRE 16 -1 (-7450 6150)(-7450 5975);
WIRE 16 -1 (-7450 5975)(-7100 5975);
WIRE 16 -1 (-7450 5975)(-7450 5850);
WIRE 16 -1 (-7100 5975)(-6750 5975);
WIRE 16 -1 (-7100 5850)(-7100 5975);
WIRE 16 -1 (-6750 5550)(-6750 5975);
WIRE 16 -1 (-6750 5550)(-6400 5550);
WIRE 16 -1 (-5550 4300)(-5400 4300);
WIRE 16 -1 (-5400 4300)(-5400 4350);
WIRE 16 -1 (-5400 4175)(-5400 4300);
WIRE 16 -1 (-5550 4350)(-5400 4350);
WIRE 16 -1 (-5400 4350)(-5400 4400);
WIRE 16 -1 (-5400 4450)(-5400 4400);
WIRE 16 -1 (-5550 4400)(-5400 4400);
WIRE 16 -1 (-5400 4450)(-5550 4450);
WIRE 16 -1 (-5550 5500)(-5450 5500);
WIRE 16 -1 (-5450 5550)(-5450 5500);
WIRE 16 -1 (-5450 5975)(-5450 5550);
WIRE 16 -1 (-5550 5550)(-5450 5550);
WIRE 16 -1 (-5450 5975)(-5325 5975);
WIRE 16 -1 (-5325 5975)(-4975 5975);
WIRE 16 -1 (-5325 5900)(-5325 5975);
WIRE 16 -1 (-4975 5975)(-4650 5975);
WIRE 16 -1 (-4975 5900)(-4975 5975);
WIRE 16 -1 (-4650 5975)(-4325 5975);
WIRE 16 -1 (-4650 5900)(-4650 5975);
WIRE 16 -1 (-4325 5975)(-4025 5975);
WIRE 16 -1 (-4325 5975)(-4325 5900);
WIRE 16 -1 (-4025 6050)(-4025 5975);
WIRE 16 -1 (-4025 5975)(-4025 5900);
WIRE 16 -1 (-5550 4600)(-5025 4600);
FORCEPROP 2 LAST SIG_NAME NC_PVDDCR_CPU0_P0_GL1_3
J 0
(-5435 4610);
DISPLAY 0.489362 (-5435 4610);
FORCEPROP 2 LASTPROP $XRERR UNIQUE?
J 0
(-4995 4600);
DISPLAY 0.638298 (-4995 4600);
PAINT MONO (-4995 4600);
DISPLAY INVISIBLE (-4995 4600);
WIRE 16 -1 (-5550 4550)(-5025 4550);
FORCEPROP 2 LAST SIG_NAME NC_PVDDCR_CPU0_P0_GL2_3
J 0
(-5435 4560);
DISPLAY 0.489362 (-5435 4560);
FORCEPROP 2 LASTPROP $XRERR UNIQUE?
J 0
(-4995 4550);
DISPLAY 0.638298 (-4995 4550);
PAINT MONO (-4995 4550);
DISPLAY INVISIBLE (-4995 4550);
WIRE 16 -1 (-4475 4625)(-4475 4350);
FORCEPROP 2 LAST SIG_NAME SW_PVDDCR_CPU0_P0_SW3_RC
J 0
(-4435 4460);
DISPLAY 0.489362 (-4435 4460);
FORCEPROP 2 LASTPROP $XRERR UNIQUE?
J 0
(-4675 4460);
DISPLAY 0.638298 (-4675 4460);
PAINT MONO (-4675 4460);
DISPLAY INVISIBLE (-4675 4460);
WIRE 16 -1 (-3625 1350)(-3200 1350);
FORCEPROP 2 LAST SIG_NAME IND_CPU0_P0_CPL3
J 0
(-3610 1360);
DISPLAY 0.489362 (-3610 1360);
WIRE 16 -1 (-1600 1600)(-1600 700);
WIRE 16 -1 (-2400 1600)(-1600 1600);
WIRE 16 -1 (-1400 1600)(-1600 1600);
WIRE 16 -1 (-1600 700)(-3875 700);
WIRE 16 -1 (-900 1600)(-1400 1600);
WIRE 16 -1 (-1400 1600)(-1400 1525);
WIRE 16 -1 (-900 1700)(-900 1600);
WIRE 16 -1 (-900 1600)(-900 1525);
WIRE 16 -1 (-1975 1200)(-1975 1350);
WIRE 16 -1 (-2400 1350)(-1975 1350);
WIRE 16 -1 (-1400 1325)(-1400 1200);
WIRE 16 -1 (-1400 1200)(-900 1200);
WIRE 16 -1 (-900 1325)(-900 1200);
WIRE 16 -1 (-900 975)(-900 1200);
WIRE 16 -1 (-1700 4900)(-1700 3950);
WIRE 16 -1 (-1700 4900)(-1500 4900);
WIRE 16 -1 (-2425 4900)(-1700 4900);
WIRE 16 -1 (-1700 3950)(-4050 3950);
WIRE 16 -1 (-1500 4900)(-1075 4900);
WIRE 16 -1 (-1500 4825)(-1500 4900);
WIRE 16 -1 (-1075 5000)(-1075 4900);
WIRE 16 -1 (-1075 4900)(-1075 4825);
WIRE 16 -1 (-3725 4650)(-3225 4650);
FORCEPROP 2 LAST SIG_NAME IND_CPU0_P0_CPL2
J 0
(-3710 4660);
DISPLAY 0.489362 (-3710 4660);
WIRE 16 -1 (-4450 5250)(-3550 5250);
FORCEPROP 2 LAST SIG_NAME SW_PVDDCR_CPU0_P0_BOOT3_RC
J 2
(-3585 5260);
DISPLAY 0.489362 (-3585 5260);
FORCEPROP 2 LASTPROP $XRERR UNIQUE?
J 0
(-3825 5260);
DISPLAY 0.638298 (-3825 5260);
PAINT MONO (-3825 5260);
DISPLAY INVISIBLE (-3825 5260);
WIRE 16 -1 (-3550 5250)(-3550 5225);
WIRE 16 -1 (-2425 4650)(-2000 4650);
FORCEPROP 2 LAST SIG_NAME IND_CPU0_P0_CPL3
J 0
(-2385 4660);
DISPLAY 0.489362 (-2385 4660);
WIRE 16 -1 (-1500 4625)(-1500 4500);
WIRE 16 -1 (-1075 4500)(-1500 4500);
WIRE 16 -1 (-1075 4625)(-1075 4500);
WIRE 16 -1 (-1075 4425)(-1075 4500);
DOT 1 (-3800 2275);
DOT 1 (-4400 1600);
DOT 1 (-4975 5975);
DOT 1 (-1075 4500);
DOT 1 (-6900 1950);
DOT 1 (-4475 4900);
DOT 1 (-7100 5975);
DOT 1 (-7450 5975);
DOT 1 (-7350 2725);
DOT 1 (-4500 2275);
DOT 1 (-4825 2275);
DOT 1 (-5200 2675);
DOT 1 (-4825 2675);
DOT 1 (-4175 2275);
DOT 1 (-3800 2675);
DOT 1 (-4500 2675);
DOT 1 (-1600 1600);
DOT 1 (-1400 1600);
DOT 1 (-900 1200);
DOT 1 (-900 1600);
DOT 1 (-4975 5575);
DOT 1 (-4325 5575);
DOT 1 (-4650 5575);
DOT 1 (-6950 5250);
DOT 1 (-1500 4900);
DOT 1 (-1075 4900);
DOT 1 (-7700 1500);
DOT 1 (-7000 2725);
DOT 1 (-5325 1000);
DOT 1 (-5325 1100);
DOT 1 (-5325 1050);
DOT 1 (-5375 2250);
DOT 1 (-4175 2675);
DOT 1 (-7450 5425);
DOT 1 (-5400 4350);
DOT 1 (-5400 4300);
DOT 1 (-5400 4400);
DOT 1 (-5450 5550);
DOT 1 (-4650 5975);
DOT 1 (-4325 5975);
DOT 1 (-4025 5975);
DOT 1 (-7775 4800);
DOT 1 (-7350 2125);
DOT 1 (-1700 4900);
DOT 1 (-5325 5975);
DOT 1 (-4025 5575);
FORCENOTE
2ND=CV+15^0TZ01
(-2550 1675) 0;
DISPLAY LEFT (-2550 1675);
DISPLAY 0.638298 (-2550 1675);
PAINT WHITE (-2550 1675);
FORCENOTE
DCR=2-3,0.27M OHM
(-2550 1725) 0;
DISPLAY LEFT (-2550 1725);
DISPLAY 0.638298 (-2550 1725);
PAINT WHITE (-2550 1725);
FORCENOTE
DCR=1-4,0.105M OHM
(-2550 1775) 0;
DISPLAY LEFT (-2550 1775);
DISPLAY 0.638298 (-2550 1775);
PAINT WHITE (-2550 1775);
FORCENOTE
11.0*7.5*12.5
(-2550 1825) 0;
DISPLAY LEFT (-2550 1825);
DISPLAY 0.638298 (-2550 1825);
PAINT WHITE (-2550 1825);
FORCENOTE
ISAT:70A@100C
(-2550 1875) 0;
DISPLAY LEFT (-2550 1875);
DISPLAY 0.638298 (-2550 1875);
PAINT WHITE (-2550 1875);
FORCENOTE
PGL6303.151HLT
(-2550 1925) 0;
DISPLAY LEFT (-2550 1925);
DISPLAY 0.638298 (-2550 1925);
PAINT WHITE (-2550 1925);
FORCENOTE
2ND=CV+15^0TZ01
(-2575 4975) 0;
DISPLAY LEFT (-2575 4975);
DISPLAY 0.638298 (-2575 4975);
PAINT WHITE (-2575 4975);
FORCENOTE
DCR=1-4,0.105M OHM
(-2575 5075) 0;
DISPLAY LEFT (-2575 5075);
DISPLAY 0.638298 (-2575 5075);
PAINT WHITE (-2575 5075);
FORCENOTE
PGL6303.151HLT
(-2575 5225) 0;
DISPLAY LEFT (-2575 5225);
DISPLAY 0.638298 (-2575 5225);
PAINT WHITE (-2575 5225);
FORCENOTE
ISAT:70A@100C
(-2575 5175) 0;
DISPLAY LEFT (-2575 5175);
DISPLAY 0.638298 (-2575 5175);
PAINT WHITE (-2575 5175);
FORCENOTE
DCR=2-3,0.27M OHM
(-2575 5025) 0;
DISPLAY LEFT (-2575 5025);
DISPLAY 0.638298 (-2575 5025);
PAINT WHITE (-2575 5025);
FORCENOTE
11.0*7.5*12.5
(-2575 5125) 0;
DISPLAY LEFT (-2575 5125);
DISPLAY 0.638298 (-2575 5125);
PAINT WHITE (-2575 5125);
FORCENOTE
PVDDCR_CPU0_P0_PHASE3
(-6550 6300) 0;
DISPLAY LEFT (-6550 6300);
DISPLAY 1.595745 (-6550 6300);
PAINT WHITE (-6550 6300);
FORCENOTE
PVDDCR_CPU0_P0_PHASE4
(-6575 2925) 0;
DISPLAY LEFT (-6575 2925);
DISPLAY 1.595745 (-6575 2925);
PAINT WHITE (-6575 2925);
QUIT
